FILE_TYPE = MACRO_DRAWING;
SET COLOR_WIRE YELLOW;
SET COLOR_PROP MONO;
SET COLOR_DOT WHITE;
SET COLOR_ARC YELLOW;
SET COLOR_BODY GREEN;
SET COLOR_NOTE MONO;
SET PROP_DISPLAY VALUE;
SET PAGE_NUMBER P226;
FORCEADD OFFPAGE..2
(4050 1725);
FORCEPROP 2 LAST $XR0 226 
J 0
(4239 1725);
DISPLAY 0.638298 (4239 1725);
PAINT MONO (4239 1725);
FORCEPROP 1 LAST COMMENT_BODY TRUE
J 0
(4005 1630);
DISPLAY 1.170213 (4005 1630);
PAINT GREEN (4005 1630);
DISPLAY INVISIBLE (4005 1630);
FORCEPROP 1 LAST OFFPAGE TRUE
J 0
(4375 1600);
DISPLAY 1.170213 (4375 1600);
PAINT GREEN (4375 1600);
DISPLAY INVISIBLE (4375 1600);
FORCEPROP 2 LAST PATH I1
J 0
(4225 1800);
DISPLAY 1.021277 (4225 1800);
PAINT ORANGE (4225 1800);
DISPLAY INVISIBLE (4225 1800);
FORCEPROP 2 LAST CDS_LIB mstr_standard
J 0
(4050 1725);
PAINT ORANGE (4050 1725);
DISPLAY INVISIBLE (4050 1725);
FORCEPROP 2 LAST ROOM VDDQ_KLM_PWR_VR
J 0
(3625 1800);
DISPLAY 1.361702 (3625 1800);
PAINT ORANGE (3625 1800);
DISPLAY INVISIBLE (3625 1800);
FORCEADD OFFPAGE..2
(4350 2425);
FORCEPROP 2 LAST $XR2 145 
J 0
(4749 2425);
DISPLAY 0.638298 (4749 2425);
PAINT MONO (4749 2425);
FORCEPROP 2 LAST $XR1 119 
J 0
(4629 2425);
DISPLAY 0.638298 (4629 2425);
PAINT MONO (4629 2425);
FORCEPROP 2 LAST $XR0 94 
J 0
(4539 2425);
DISPLAY 0.638298 (4539 2425);
PAINT MONO (4539 2425);
FORCEPROP 1 LAST COMMENT_BODY TRUE
J 0
(4305 2330);
DISPLAY 1.170213 (4305 2330);
PAINT GREEN (4305 2330);
DISPLAY INVISIBLE (4305 2330);
FORCEPROP 1 LAST OFFPAGE TRUE
J 0
(4675 2300);
DISPLAY 1.170213 (4675 2300);
PAINT GREEN (4675 2300);
DISPLAY INVISIBLE (4675 2300);
FORCEPROP 2 LAST PATH I10
J 0
(4525 2500);
DISPLAY 1.021277 (4525 2500);
PAINT ORANGE (4525 2500);
DISPLAY INVISIBLE (4525 2500);
FORCEPROP 2 LAST CDS_LIB mstr_standard
J 0
(4350 2425);
PAINT ORANGE (4350 2425);
DISPLAY INVISIBLE (4350 2425);
FORCEPROP 2 LAST ROOM VDDQ_KLM_PWR_VR
J 0
(3925 2500);
DISPLAY 1.361702 (3925 2500);
PAINT ORANGE (3925 2500);
DISPLAY INVISIBLE (3925 2500);
FORCEADD OFFPAGE..2
(4350 2525);
FORCEPROP 2 LAST $XR0 230 
J 0
(4539 2525);
DISPLAY 0.638298 (4539 2525);
PAINT MONO (4539 2525);
FORCEPROP 1 LAST COMMENT_BODY TRUE
J 0
(4305 2430);
DISPLAY 1.170213 (4305 2430);
PAINT GREEN (4305 2430);
DISPLAY INVISIBLE (4305 2430);
FORCEPROP 1 LAST OFFPAGE TRUE
J 0
(4675 2400);
DISPLAY 1.170213 (4675 2400);
PAINT GREEN (4675 2400);
DISPLAY INVISIBLE (4675 2400);
FORCEPROP 2 LAST PATH I11
J 0
(4525 2600);
DISPLAY 1.021277 (4525 2600);
PAINT ORANGE (4525 2600);
DISPLAY INVISIBLE (4525 2600);
FORCEPROP 2 LAST CDS_LIB mstr_standard
J 0
(4350 2525);
PAINT ORANGE (4350 2525);
DISPLAY INVISIBLE (4350 2525);
FORCEPROP 2 LAST ROOM VDDQ_KLM_PWR_VR
J 0
(3925 2600);
DISPLAY 1.361702 (3925 2600);
PAINT ORANGE (3925 2600);
DISPLAY INVISIBLE (3925 2600);
FORCEADD RES..2
(2750 3050);
FORCEPROP 1 LAST PART_NUMBER G21796-311
J 0
(2790 2925);
DISPLAY 0.617021 (2790 2925);
PAINT BLUE (2790 2925);
FORCEPROP 1 LAST LOCATION R1B13
J 0
(2795 3175);
DISPLAY 0.617021 (2795 3175);
PAINT AQUA (2795 3175);
FORCEPROP 1 LAST VALUE 2.26K
J 0
(2795 3125);
DISPLAY 0.617021 (2795 3125);
PAINT SKYBLUE (2795 3125);
FORCEPROP 1 LAST TOLERANCE 1.0%
J 0
(2795 3075);
DISPLAY 0.617021 (2795 3075);
PAINT SKYBLUE (2795 3075);
FORCEPROP 1 LASTPIN (2750 3150) $PN 1
J 0
(2755 3112);
DISPLAY 0.617021 (2755 3112);
PAINT ORANGE (2755 3112);
FORCEPROP 1 LAST MATERIAL EMPTY
J 0
(2790 2975);
DISPLAY 0.617021 (2790 2975);
PAINT RED (2790 2975);
FORCEPROP 1 LAST PACK_TYPE 0402
J 0
(2790 2875);
DISPLAY 0.617021 (2790 2875);
PAINT SKYBLUE (2790 2875);
FORCEPROP 1 LAST WATTAGE 1/16W
J 0
(2790 3025);
DISPLAY 0.617021 (2790 3025);
PAINT SKYBLUE (2790 3025);
FORCEPROP 1 LASTPIN (2750 2950) $PN 2
J 0
(2755 2960);
DISPLAY 0.617021 (2755 2960);
PAINT ORANGE (2755 2960);
FORCEPROP 2 LAST SEC_TYPE 0402
J 0
(2800 3300);
DISPLAY 1.021277 (2800 3300);
PAINT ORANGE (2800 3300);
DISPLAY INVISIBLE (2800 3300);
FORCEPROP 2 LAST SEC 1
J 0
(2800 3300);
DISPLAY 0.680851 (2800 3300);
PAINT MONO (2800 3300);
DISPLAY INVISIBLE (2800 3300);
FORCEPROP 1 LAST PATH I13
J 0
(2800 3225);
DISPLAY 0.978723 (2800 3225);
PAINT WHITE (2800 3225);
DISPLAY INVISIBLE (2800 3225);
FORCEPROP 2 LAST CDS_LOCATION R1B13
J 0
(2795 3175);
DISPLAY 0.617021 (2795 3175);
PAINT AQUA (2795 3175);
DISPLAY INVISIBLE (2795 3175);
FORCEPROP 2 LAST CDS_LIB mstr_discrete
J 0
(2750 3050);
PAINT ORANGE (2750 3050);
DISPLAY INVISIBLE (2750 3050);
FORCEPROP 2 LAST ROOM VDDQ_KLM_PWR_VR
J 0
(2800 3025);
DISPLAY 1.361702 (2800 3025);
PAINT ORANGE (2800 3025);
DISPLAY INVISIBLE (2800 3025);
FORCEADD RES..1
(3375 2525);
FORCEPROP 1 LASTPIN (3275 2525) $PN 1
J 0
(3287 2537);
DISPLAY 0.617021 (3287 2537);
PAINT ORANGE (3287 2537);
FORCEPROP 1 LASTPIN (3475 2525) $PN 2
J 0
(3437 2537);
DISPLAY 0.617021 (3437 2537);
PAINT ORANGE (3437 2537);
FORCEPROP 1 LAST WATTAGE 1/16W
J 2
(3300 2675);
DISPLAY 0.617021 (3300 2675);
PAINT SKYBLUE (3300 2675);
FORCEPROP 1 LAST MATERIAL CHIP
J 0
(3175 2625);
DISPLAY 0.617021 (3175 2625);
PAINT SKYBLUE (3175 2625);
FORCEPROP 1 LAST VALUE 22.1
J 2
(3275 2575);
DISPLAY 0.617021 (3275 2575);
PAINT SKYBLUE (3275 2575);
FORCEPROP 1 LAST LOCATION R1B5
J 0
(3325 2575);
DISPLAY 0.617021 (3325 2575);
PAINT AQUA (3325 2575);
FORCEPROP 1 LAST PACK_TYPE 0402
J 0
(3475 2675);
DISPLAY 0.617021 (3475 2675);
PAINT SKYBLUE (3475 2675);
FORCEPROP 1 LAST TOLERANCE 1.0%
J 0
(3500 2575);
DISPLAY 0.617021 (3500 2575);
PAINT SKYBLUE (3500 2575);
FORCEPROP 1 LAST PART_NUMBER G21796-250
J 0
(3325 2625);
DISPLAY 0.617021 (3325 2625);
PAINT BLUE (3325 2625);
FORCEPROP 2 LAST CDS_LIB mstr_discrete
J 0
(3375 2525);
PAINT MONO (3375 2525);
DISPLAY INVISIBLE (3375 2525);
FORCEPROP 2 LAST ROOM VDDQ_KLM_PWR_VR
J 0
(3325 2625);
DISPLAY 1.361702 (3325 2625);
PAINT ORANGE (3325 2625);
DISPLAY INVISIBLE (3325 2625);
FORCEPROP 1 LAST PATH I14
J 0
(3325 2675);
DISPLAY 0.978723 (3325 2675);
PAINT WHITE (3325 2675);
DISPLAY INVISIBLE (3325 2675);
FORCEPROP 2 LAST CDS_LOCATION R1B5
J 0
(3325 2575);
DISPLAY 0.617021 (3325 2575);
PAINT AQUA (3325 2575);
DISPLAY INVISIBLE (3325 2575);
FORCEPROP 2 LAST SEC 1
J 0
(3325 2725);
DISPLAY 0.680851 (3325 2725);
PAINT MONO (3325 2725);
DISPLAY INVISIBLE (3325 2725);
FORCEPROP 2 LAST SEC_TYPE 0402
J 0
(3325 2725);
DISPLAY 1.021277 (3325 2725);
PAINT ORANGE (3325 2725);
DISPLAY INVISIBLE (3325 2725);
FORCEADD P3V3_STBY..1
(2450 3700);
FORCEPROP 3 LASTPIN (2450 3650) SIG_NAME P3V3_STBY\g
J 0
(2460 3660);
DISPLAY 0.659574 (2460 3660);
PAINT MONO (2460 3660);
DISPLAY INVISIBLE (2460 3660);
FORCEPROP 1 LAST HDL_POWER P3V3_STBY
J 0
(2150 3575);
DISPLAY 0.872340 (2150 3575);
PAINT ORANGE (2150 3575);
DISPLAY INVISIBLE (2150 3575);
FORCEPROP 1 LAST BODY_TYPE PLUMBING
J 0
(2405 3657);
DISPLAY 0.340426 (2405 3657);
PAINT GREEN (2405 3657);
DISPLAY INVISIBLE (2405 3657);
FORCEPROP 1 LAST VOLTAGE 3.3V
J 0
(2405 3657);
DISPLAY 0.340426 (2405 3657);
PAINT SKYBLUE (2405 3657);
DISPLAY INVISIBLE (2405 3657);
FORCEPROP 1 LAST SIZE 1B
J 0
(2495 3722);
DISPLAY 0.340426 (2495 3722);
PAINT GREEN (2495 3722);
DISPLAY INVISIBLE (2495 3722);
FORCEPROP 2 LAST CDS_LIB mstr_symbols
J 0
(2450 3700);
PAINT ORANGE (2450 3700);
DISPLAY INVISIBLE (2450 3700);
FORCEPROP 1 LAST PATH I15
J 0
(2495 3702);
DISPLAY 0.340426 (2495 3702);
PAINT GREEN (2495 3702);
DISPLAY INVISIBLE (2495 3702);
FORCEADD RES..1
(2575 2375);
FORCEPROP 1 LASTPIN (2475 2375) $PN 1
J 0
(2487 2387);
DISPLAY 0.617021 (2487 2387);
PAINT ORANGE (2487 2387);
FORCEPROP 1 LAST WATTAGE 1/16W
J 2
(2475 2325);
DISPLAY 0.617021 (2475 2325);
PAINT SKYBLUE (2475 2325);
FORCEPROP 1 LAST VALUE 0.0
J 2
(2550 2325);
DISPLAY 0.617021 (2550 2325);
PAINT SKYBLUE (2550 2325);
FORCEPROP 1 LAST PART_NUMBER G21497-005
J 0
(2450 2300);
DISPLAY 0.617021 (2450 2300);
PAINT BLUE (2450 2300);
FORCEPROP 1 LASTPIN (2675 2375) $PN 2
J 0
(2637 2387);
DISPLAY 0.617021 (2637 2387);
PAINT ORANGE (2637 2387);
FORCEPROP 1 LAST PACK_TYPE 0402
J 0
(2675 2325);
DISPLAY 0.617021 (2675 2325);
PAINT SKYBLUE (2675 2325);
FORCEPROP 1 LAST LOCATION R1B11
J 0
(2625 2425);
DISPLAY 0.617021 (2625 2425);
PAINT AQUA (2625 2425);
FORCEPROP 1 LAST TOLERANCE 5%
J 0
(2575 2325);
DISPLAY 0.617021 (2575 2325);
PAINT SKYBLUE (2575 2325);
FORCEPROP 1 LAST MATERIAL CHIP
J 0
(2800 2325);
DISPLAY 0.617021 (2800 2325);
PAINT SKYBLUE (2800 2325);
FORCEPROP 2 LAST ROOM VDDQ_KLM_PWR_VR
J 0
(2525 2475);
DISPLAY 1.361702 (2525 2475);
PAINT ORANGE (2525 2475);
DISPLAY INVISIBLE (2525 2475);
FORCEPROP 1 LAST PATH I16
J 0
(2525 2525);
DISPLAY 0.978723 (2525 2525);
PAINT WHITE (2525 2525);
DISPLAY INVISIBLE (2525 2525);
FORCEPROP 2 LAST SEC_TYPE 0402
J 0
(2525 2600);
DISPLAY 1.021277 (2525 2600);
PAINT ORANGE (2525 2600);
DISPLAY INVISIBLE (2525 2600);
FORCEPROP 2 LAST SEC 1
J 0
(2525 2600);
DISPLAY 0.680851 (2525 2600);
PAINT MONO (2525 2600);
DISPLAY INVISIBLE (2525 2600);
FORCEPROP 2 LAST CDS_LIB mstr_discrete
J 0
(2575 2375);
PAINT ORANGE (2575 2375);
DISPLAY INVISIBLE (2575 2375);
FORCEPROP 2 LAST CDS_LOCATION R1B11
J 0
(2625 2425);
DISPLAY 0.617021 (2625 2425);
PAINT AQUA (2625 2425);
DISPLAY INVISIBLE (2625 2425);
FORCEADD RES..2
(2350 3025);
FORCEPROP 1 LASTPIN (2350 3125) $PN 1
J 0
(2355 3087);
DISPLAY 0.617021 (2355 3087);
PAINT ORANGE (2355 3087);
FORCEPROP 1 LAST VALUE 1.00K
J 0
(2395 3100);
DISPLAY 0.617021 (2395 3100);
PAINT SKYBLUE (2395 3100);
FORCEPROP 1 LAST LOCATION R1B2
J 0
(2395 3150);
DISPLAY 0.617021 (2395 3150);
PAINT AQUA (2395 3150);
FORCEPROP 1 LAST TOLERANCE 1%
J 0
(2395 3050);
DISPLAY 0.617021 (2395 3050);
PAINT SKYBLUE (2395 3050);
FORCEPROP 1 LAST PART_NUMBER G21796-026
J 0
(2390 2900);
DISPLAY 0.617021 (2390 2900);
PAINT BLUE (2390 2900);
FORCEPROP 1 LASTPIN (2350 2925) $PN 2
J 0
(2355 2935);
DISPLAY 0.617021 (2355 2935);
PAINT ORANGE (2355 2935);
FORCEPROP 1 LAST WATTAGE 1/16W
J 0
(2390 3000);
DISPLAY 0.617021 (2390 3000);
PAINT SKYBLUE (2390 3000);
FORCEPROP 1 LAST MATERIAL CHIP
J 0
(2390 2950);
DISPLAY 0.617021 (2390 2950);
PAINT SKYBLUE (2390 2950);
FORCEPROP 1 LAST PACK_TYPE 0402
J 0
(2390 2850);
DISPLAY 0.617021 (2390 2850);
PAINT SKYBLUE (2390 2850);
FORCEPROP 2 LAST SEC_TYPE 0402
J 0
(2400 3275);
DISPLAY 1.021277 (2400 3275);
PAINT ORANGE (2400 3275);
DISPLAY INVISIBLE (2400 3275);
FORCEPROP 1 LAST PATH I17
J 0
(2400 3200);
DISPLAY 0.978723 (2400 3200);
PAINT WHITE (2400 3200);
DISPLAY INVISIBLE (2400 3200);
FORCEPROP 2 LAST CDS_LOCATION R1B2
J 0
(2395 3150);
DISPLAY 0.617021 (2395 3150);
PAINT AQUA (2395 3150);
DISPLAY INVISIBLE (2395 3150);
FORCEPROP 2 LAST SEC 1
J 0
(2400 3275);
DISPLAY 0.680851 (2400 3275);
PAINT MONO (2400 3275);
DISPLAY INVISIBLE (2400 3275);
FORCEPROP 2 LAST ROOM VDDQ_KLM_PWR_VR
J 0
(2400 3200);
DISPLAY 1.361702 (2400 3200);
PAINT ORANGE (2400 3200);
DISPLAY INVISIBLE (2400 3200);
FORCEPROP 2 LAST CDS_LIB mstr_discrete
J 2
(2350 3025);
PAINT ORANGE (2350 3025);
DISPLAY INVISIBLE (2350 3025);
FORCEADD OFFPAGE..1
R 2
(4025 2025);
FORCEPROP 2 LAST $XR11 223 
J 0
(4691 1989);
DISPLAY 0.638298 (4691 1989);
PAINT MONO (4691 1989);
FORCEPROP 2 LAST $XR10 218 
J 0
(4571 1989);
DISPLAY 0.638298 (4571 1989);
PAINT MONO (4571 1989);
FORCEPROP 2 LAST $XR9 215 
J 0
(4451 1989);
DISPLAY 0.638298 (4451 1989);
PAINT MONO (4451 1989);
FORCEPROP 2 LAST $XR8 206 
J 0
(4331 1989);
DISPLAY 0.638298 (4331 1989);
PAINT MONO (4331 1989);
FORCEPROP 2 LAST $XR7 201 
J 0
(5051 2025);
DISPLAY 0.638298 (5051 2025);
PAINT MONO (5051 2025);
FORCEPROP 2 LAST $XR6 194 
J 0
(4931 2025);
DISPLAY 0.638298 (4931 2025);
PAINT MONO (4931 2025);
FORCEPROP 2 LAST $XR5 193 
J 0
(4811 2025);
DISPLAY 0.638298 (4811 2025);
PAINT MONO (4811 2025);
FORCEPROP 2 LAST $XR4 235 
J 0
(4691 2025);
DISPLAY 0.638298 (4691 2025);
PAINT MONO (4691 2025);
FORCEPROP 2 LAST $XR3 213 
J 0
(4571 2025);
DISPLAY 0.638298 (4571 2025);
PAINT MONO (4571 2025);
FORCEPROP 2 LAST $XR2 211 
J 0
(4451 2025);
DISPLAY 0.638298 (4451 2025);
PAINT MONO (4451 2025);
FORCEPROP 2 LAST $XR1 159 
J 0
(4331 2025);
DISPLAY 0.638298 (4331 2025);
PAINT MONO (4331 2025);
FORCEPROP 2 LAST $XR0 138 
J 0
(4211 2025);
DISPLAY 0.638298 (4211 2025);
PAINT MONO (4211 2025);
FORCEPROP 1 LAST COMMENT_BODY TRUE
J 2
(3900 1925);
DISPLAY 1.170213 (3900 1925);
PAINT GREEN (3900 1925);
DISPLAY INVISIBLE (3900 1925);
FORCEPROP 1 LAST OFFPAGE TRUE
J 2
(3700 1900);
DISPLAY 1.170213 (3700 1900);
PAINT GREEN (3700 1900);
DISPLAY INVISIBLE (3700 1900);
FORCEPROP 2 LAST PATH I18
J 0
(4200 2100);
DISPLAY 1.021277 (4200 2100);
PAINT ORANGE (4200 2100);
DISPLAY INVISIBLE (4200 2100);
FORCEPROP 2 LAST ROOM VDDQ_KLM_PWR_VR
J 0
(3600 2100);
DISPLAY 1.361702 (3600 2100);
PAINT ORANGE (3600 2100);
DISPLAY INVISIBLE (3600 2100);
FORCEPROP 2 LAST CDS_LIB mstr_standard
J 0
(4025 2025);
PAINT ORANGE (4025 2025);
DISPLAY INVISIBLE (4025 2025);
FORCEADD OFFPAGE..3
(4025 1975);
FORCEPROP 2 LAST $XR11 235 
J 0
(5079 1975);
DISPLAY 0.638298 (5079 1975);
PAINT MONO (5079 1975);
FORCEPROP 2 LAST $XR10 223 
J 0
(4959 1975);
DISPLAY 0.638298 (4959 1975);
PAINT MONO (4959 1975);
FORCEPROP 2 LAST $XR9 218 
J 0
(4839 1975);
DISPLAY 0.638298 (4839 1975);
PAINT MONO (4839 1975);
FORCEPROP 2 LAST $XR8 215 
J 0
(5079 1939);
DISPLAY 0.638298 (5079 1939);
PAINT MONO (5079 1939);
FORCEPROP 2 LAST $XR7 213 
J 0
(4959 1939);
DISPLAY 0.638298 (4959 1939);
PAINT MONO (4959 1939);
FORCEPROP 2 LAST $XR6 211 
J 0
(4839 1939);
DISPLAY 0.638298 (4839 1939);
PAINT MONO (4839 1939);
FORCEPROP 2 LAST $XR5 206 
J 0
(4719 1939);
DISPLAY 0.638298 (4719 1939);
PAINT MONO (4719 1939);
FORCEPROP 2 LAST $XR4 201 
J 0
(4599 1939);
DISPLAY 0.638298 (4599 1939);
PAINT MONO (4599 1939);
FORCEPROP 2 LAST $XR3 194 
J 0
(4479 1939);
DISPLAY 0.638298 (4479 1939);
PAINT MONO (4479 1939);
FORCEPROP 2 LAST $XR2 193 
J 0
(4359 1939);
DISPLAY 0.638298 (4359 1939);
PAINT MONO (4359 1939);
FORCEPROP 2 LAST $XR1 159 
J 0
(4239 1939);
DISPLAY 0.638298 (4239 1939);
PAINT MONO (4239 1939);
FORCEPROP 2 LAST $XR0 138 
J 0
(4239 1975);
DISPLAY 0.638298 (4239 1975);
PAINT MONO (4239 1975);
FORCEPROP 1 LAST COMMENT_BODY TRUE
J 0
(3975 1875);
DISPLAY 1.170213 (3975 1875);
PAINT GREEN (3975 1875);
DISPLAY INVISIBLE (3975 1875);
FORCEPROP 1 LAST OFFPAGE TRUE
J 0
(4350 1850);
DISPLAY 1.170213 (4350 1850);
PAINT GREEN (4350 1850);
DISPLAY INVISIBLE (4350 1850);
FORCEPROP 2 LAST PATH I19
J 0
(4225 2050);
DISPLAY 1.021277 (4225 2050);
PAINT ORANGE (4225 2050);
DISPLAY INVISIBLE (4225 2050);
FORCEPROP 2 LAST ROOM VDDQ_KLM_PWR_VR
J 0
(3625 2050);
DISPLAY 1.361702 (3625 2050);
PAINT ORANGE (3625 2050);
DISPLAY INVISIBLE (3625 2050);
FORCEPROP 2 LAST CDS_LIB mstr_standard
J 0
(4025 1975);
PAINT ORANGE (4025 1975);
DISPLAY INVISIBLE (4025 1975);
FORCEADD OFFPAGE..2
(4050 1475);
FORCEPROP 2 LAST $XR0 227 
J 0
(4239 1475);
DISPLAY 0.638298 (4239 1475);
PAINT MONO (4239 1475);
FORCEPROP 1 LAST COMMENT_BODY TRUE
J 0
(4005 1380);
DISPLAY 1.170213 (4005 1380);
PAINT GREEN (4005 1380);
DISPLAY INVISIBLE (4005 1380);
FORCEPROP 1 LAST OFFPAGE TRUE
J 0
(4375 1350);
DISPLAY 1.170213 (4375 1350);
PAINT GREEN (4375 1350);
DISPLAY INVISIBLE (4375 1350);
FORCEPROP 2 LAST PATH I2
J 0
(4225 1550);
DISPLAY 1.021277 (4225 1550);
PAINT ORANGE (4225 1550);
DISPLAY INVISIBLE (4225 1550);
FORCEPROP 2 LAST ROOM VDDQ_KLM_PWR_VR
J 0
(3625 1550);
DISPLAY 1.361702 (3625 1550);
PAINT ORANGE (3625 1550);
DISPLAY INVISIBLE (3625 1550);
FORCEPROP 2 LAST CDS_LIB mstr_standard
J 0
(4050 1475);
PAINT ORANGE (4050 1475);
DISPLAY INVISIBLE (4050 1475);
FORCEADD OFFPAGE..3
(4025 1675);
FORCEPROP 2 LAST $XR2 223 
J 0
(4449 1675);
DISPLAY 0.638298 (4449 1675);
PAINT MONO (4449 1675);
FORCEPROP 2 LAST $XR1 193 
J 0
(4329 1675);
DISPLAY 0.638298 (4329 1675);
PAINT MONO (4329 1675);
FORCEPROP 2 LAST $XR0 55 
J 0
(4239 1675);
DISPLAY 0.638298 (4239 1675);
PAINT MONO (4239 1675);
FORCEPROP 1 LAST COMMENT_BODY TRUE
J 0
(3975 1575);
DISPLAY 1.170213 (3975 1575);
PAINT GREEN (3975 1575);
DISPLAY INVISIBLE (3975 1575);
FORCEPROP 1 LAST OFFPAGE TRUE
J 0
(4350 1550);
DISPLAY 1.170213 (4350 1550);
PAINT GREEN (4350 1550);
DISPLAY INVISIBLE (4350 1550);
FORCEPROP 2 LAST PATH I20
J 0
(4225 1750);
DISPLAY 1.021277 (4225 1750);
PAINT ORANGE (4225 1750);
DISPLAY INVISIBLE (4225 1750);
FORCEPROP 2 LAST CDS_LIB mstr_standard
J 0
(4025 1675);
PAINT ORANGE (4025 1675);
DISPLAY INVISIBLE (4025 1675);
FORCEPROP 2 LAST ROOM VDDQ_KLM_PWR_VR
J 0
(3625 1750);
DISPLAY 1.361702 (3625 1750);
PAINT ORANGE (3625 1750);
DISPLAY INVISIBLE (3625 1750);
FORCEADD RES..1
(3100 2025);
FORCEPROP 1 LAST WATTAGE 1/16W
J 2
(3075 1875);
DISPLAY 0.617021 (3075 1875);
PAINT SKYBLUE (3075 1875);
FORCEPROP 1 LAST VALUE 20.0
J 2
(3075 1925);
DISPLAY 0.617021 (3075 1925);
PAINT SKYBLUE (3075 1925);
FORCEPROP 1 LAST MATERIAL CHIP
J 0
(3100 1875);
DISPLAY 0.617021 (3100 1875);
PAINT SKYBLUE (3100 1875);
FORCEPROP 1 LAST PACK_TYPE 0402
J 0
(3100 1825);
DISPLAY 0.617021 (3100 1825);
PAINT SKYBLUE (3100 1825);
FORCEPROP 1 LAST TOLERANCE 1%
J 0
(3100 1925);
DISPLAY 0.617021 (3100 1925);
PAINT SKYBLUE (3100 1925);
FORCEPROP 1 LAST PART_NUMBER G21796-173
J 0
(3050 2125);
DISPLAY 0.617021 (3050 2125);
PAINT BLUE (3050 2125);
FORCEPROP 1 LAST LOCATION R1B6
J 0
(3050 2075);
DISPLAY 0.617021 (3050 2075);
PAINT AQUA (3050 2075);
FORCEPROP 1 LASTPIN (3000 2025) $PN 1
J 0
(3012 2037);
DISPLAY 0.787234 (3012 2037);
PAINT ORANGE (3012 2037);
DISPLAY INVISIBLE (3012 2037);
FORCEPROP 1 LASTPIN (3200 2025) $PN 2
J 0
(3162 2037);
DISPLAY 0.787234 (3162 2037);
PAINT ORANGE (3162 2037);
DISPLAY INVISIBLE (3162 2037);
FORCEPROP 2 LAST CDS_LIB mstr_discrete
J 0
(3100 2025);
PAINT ORANGE (3100 2025);
DISPLAY INVISIBLE (3100 2025);
FORCEPROP 2 LAST ROOM VDDQ_KLM_PWR_VR
J 0
(3050 2125);
DISPLAY 1.361702 (3050 2125);
PAINT ORANGE (3050 2125);
DISPLAY INVISIBLE (3050 2125);
FORCEPROP 1 LAST PATH I21
J 0
(3050 2175);
DISPLAY 0.978723 (3050 2175);
PAINT WHITE (3050 2175);
DISPLAY INVISIBLE (3050 2175);
FORCEPROP 2 LAST CDS_SEC 1
J 0
(3050 2225);
PAINT MONO (3050 2225);
DISPLAY INVISIBLE (3050 2225);
FORCEPROP 2 LAST $SEC 1
J 0
(3050 2225);
PAINT MONO (3050 2225);
DISPLAY INVISIBLE (3050 2225);
FORCEPROP 2 LAST CDS_LOCATION R1B6
J 0
(3050 2075);
DISPLAY 0.617021 (3050 2075);
PAINT AQUA (3050 2075);
DISPLAY INVISIBLE (3050 2075);
FORCEADD RES..1
(2775 1975);
FORCEPROP 1 LAST VALUE 20.0
J 2
(2750 1875);
DISPLAY 0.617021 (2750 1875);
PAINT SKYBLUE (2750 1875);
FORCEPROP 1 LAST WATTAGE 1/16W
J 2
(2750 1825);
DISPLAY 0.617021 (2750 1825);
PAINT SKYBLUE (2750 1825);
FORCEPROP 1 LAST MATERIAL CHIP
J 0
(2775 1825);
DISPLAY 0.617021 (2775 1825);
PAINT SKYBLUE (2775 1825);
FORCEPROP 1 LAST PACK_TYPE 0402
J 0
(2775 1775);
DISPLAY 0.617021 (2775 1775);
PAINT SKYBLUE (2775 1775);
FORCEPROP 1 LAST TOLERANCE 1%
J 0
(2775 1875);
DISPLAY 0.617021 (2775 1875);
PAINT SKYBLUE (2775 1875);
FORCEPROP 1 LAST LOCATION R1B7
J 0
(2725 2025);
DISPLAY 0.617021 (2725 2025);
PAINT AQUA (2725 2025);
FORCEPROP 1 LAST PART_NUMBER G21796-173
J 0
(2725 2075);
DISPLAY 0.617021 (2725 2075);
PAINT BLUE (2725 2075);
FORCEPROP 1 LASTPIN (2675 1975) $PN 1
J 0
(2687 1987);
DISPLAY 0.787234 (2687 1987);
PAINT ORANGE (2687 1987);
DISPLAY INVISIBLE (2687 1987);
FORCEPROP 2 LAST CDS_LIB mstr_discrete
J 0
(2775 1975);
PAINT ORANGE (2775 1975);
DISPLAY INVISIBLE (2775 1975);
FORCEPROP 1 LASTPIN (2875 1975) $PN 2
J 0
(2837 1987);
DISPLAY 0.787234 (2837 1987);
PAINT ORANGE (2837 1987);
DISPLAY INVISIBLE (2837 1987);
FORCEPROP 2 LAST CDS_LOCATION R1B7
J 0
(2725 2025);
DISPLAY 0.617021 (2725 2025);
PAINT AQUA (2725 2025);
DISPLAY INVISIBLE (2725 2025);
FORCEPROP 2 LAST ROOM VDDQ_KLM_PWR_VR
J 0
(2725 2075);
DISPLAY 1.361702 (2725 2075);
PAINT ORANGE (2725 2075);
DISPLAY INVISIBLE (2725 2075);
FORCEPROP 1 LAST PATH I22
J 0
(2725 2125);
DISPLAY 0.978723 (2725 2125);
PAINT WHITE (2725 2125);
DISPLAY INVISIBLE (2725 2125);
FORCEPROP 2 LAST $SEC 1
J 0
(2725 2175);
PAINT MONO (2725 2175);
DISPLAY INVISIBLE (2725 2175);
FORCEPROP 2 LAST CDS_SEC 1
J 0
(2725 2175);
PAINT MONO (2725 2175);
DISPLAY INVISIBLE (2725 2175);
FORCEADD RES..1
(2775 1675);
FORCEPROP 1 LAST WATTAGE 1/16W
J 2
(2750 1525);
DISPLAY 0.617021 (2750 1525);
PAINT SKYBLUE (2750 1525);
FORCEPROP 1 LAST MATERIAL CHIP
J 0
(2775 1525);
DISPLAY 0.617021 (2775 1525);
PAINT SKYBLUE (2775 1525);
FORCEPROP 1 LASTPIN (2675 1675) $PN 1
J 0
(2687 1687);
DISPLAY 0.617021 (2687 1687);
PAINT ORANGE (2687 1687);
FORCEPROP 1 LAST TOLERANCE 5%
J 0
(2725 1575);
DISPLAY 0.617021 (2725 1575);
PAINT SKYBLUE (2725 1575);
FORCEPROP 1 LAST VALUE 0.0
J 2
(2675 1575);
DISPLAY 0.617021 (2675 1575);
PAINT SKYBLUE (2675 1575);
FORCEPROP 1 LAST PART_NUMBER G21497-005
J 0
(2625 1625);
DISPLAY 0.617021 (2625 1625);
PAINT BLUE (2625 1625);
FORCEPROP 1 LAST LOCATION R1B10
J 0
(2725 1725);
DISPLAY 0.617021 (2725 1725);
PAINT AQUA (2725 1725);
FORCEPROP 1 LASTPIN (2875 1675) $PN 2
J 0
(2837 1687);
DISPLAY 0.617021 (2837 1687);
PAINT ORANGE (2837 1687);
FORCEPROP 1 LAST PACK_TYPE 0402
J 0
(2850 1575);
DISPLAY 0.617021 (2850 1575);
PAINT SKYBLUE (2850 1575);
FORCEPROP 2 LAST CDS_LOCATION R1B10
J 0
(2725 1725);
DISPLAY 0.617021 (2725 1725);
PAINT AQUA (2725 1725);
DISPLAY INVISIBLE (2725 1725);
FORCEPROP 2 LAST CDS_LIB mstr_discrete
J 0
(2775 1675);
PAINT ORANGE (2775 1675);
DISPLAY INVISIBLE (2775 1675);
FORCEPROP 2 LAST ROOM VDDQ_KLM_PWR_VR
J 0
(2725 1775);
DISPLAY 1.361702 (2725 1775);
PAINT ORANGE (2725 1775);
DISPLAY INVISIBLE (2725 1775);
FORCEPROP 2 LAST SEC_TYPE 0402
J 0
(2725 1875);
DISPLAY 1.021277 (2725 1875);
PAINT ORANGE (2725 1875);
DISPLAY INVISIBLE (2725 1875);
FORCEPROP 2 LAST SEC 1
J 0
(2725 1875);
DISPLAY 0.680851 (2725 1875);
PAINT MONO (2725 1875);
DISPLAY INVISIBLE (2725 1875);
FORCEPROP 1 LAST PATH I23
J 0
(2725 1825);
DISPLAY 0.978723 (2725 1825);
PAINT WHITE (2725 1825);
DISPLAY INVISIBLE (2725 1825);
FORCEADD GND..1
(2000 800);
FORCEPROP 3 LASTPIN (2000 850) SIG_NAME GND\g
J 0
(2010 860);
DISPLAY 0.659574 (2010 860);
PAINT MONO (2010 860);
DISPLAY INVISIBLE (2010 860);
FORCEPROP 1 LAST HDL_POWER GND
J 0
(2000 950);
DISPLAY 1.170213 (2000 950);
PAINT GREEN (2000 950);
DISPLAY INVISIBLE (2000 950);
FORCEPROP 1 LAST BODY_TYPE PLUMBING
J 0
(1955 757);
DISPLAY 0.340426 (1955 757);
PAINT GREEN (1955 757);
DISPLAY INVISIBLE (1955 757);
FORCEPROP 1 LAST SIZE 1B
J 0
(2075 750);
DISPLAY 1.170213 (2075 750);
PAINT AQUA (2075 750);
DISPLAY INVISIBLE (2075 750);
FORCEPROP 1 LAST PATH I24
J 0
(2075 800);
DISPLAY 0.872340 (2075 800);
PAINT AQUA (2075 800);
DISPLAY INVISIBLE (2075 800);
FORCEPROP 1 LAST VOLTAGE 0
J 0
(2000 800);
PAINT SKYBLUE (2000 800);
DISPLAY INVISIBLE (2000 800);
FORCEPROP 2 LAST CDS_LIB mstr_symbols
J 0
(2000 800);
PAINT ORANGE (2000 800);
DISPLAY INVISIBLE (2000 800);
FORCEPROP 2 LAST ROOM VDDQ_KLM_PWR_VR
J 0
(1425 875);
DISPLAY 1.361702 (1425 875);
PAINT ORANGE (1425 875);
DISPLAY INVISIBLE (1425 875);
FORCEADD CAP_A..1
(1525 3075);
FORCEPROP 1 LAST LOCATION C1B6
J 0
(1575 3175);
DISPLAY 0.617021 (1575 3175);
PAINT AQUA (1575 3175);
FORCEPROP 1 LAST VALUE 1.0UF
J 0
(1575 3125);
DISPLAY 0.617021 (1575 3125);
PAINT SKYBLUE (1575 3125);
FORCEPROP 1 LAST VOLTAGE 6.3V
J 0
(1575 3075);
DISPLAY 0.617021 (1575 3075);
PAINT SKYBLUE (1575 3075);
FORCEPROP 1 LAST PART_NUMBER D97712-004
J 0
(1575 2925);
DISPLAY 0.617021 (1575 2925);
PAINT BLUE (1575 2925);
FORCEPROP 1 LAST TOLERANCE 10%
J 0
(1575 3025);
DISPLAY 0.617021 (1575 3025);
PAINT SKYBLUE (1575 3025);
FORCEPROP 1 LAST PACK_TYPE 0402V
J 0
(1575 2875);
DISPLAY 0.617021 (1575 2875);
PAINT SKYBLUE (1575 2875);
FORCEPROP 1 LAST MATERIAL X6S
J 0
(1575 2975);
DISPLAY 0.617021 (1575 2975);
PAINT SKYBLUE (1575 2975);
FORCEPROP 2 LAST CDS_LOCATION C1B6
J 0
(1575 3175);
DISPLAY 0.617021 (1575 3175);
PAINT AQUA (1575 3175);
DISPLAY INVISIBLE (1575 3175);
FORCEPROP 2 LAST CDS_SEC 1
J 0
(1575 3275);
DISPLAY 1.021277 (1575 3275);
PAINT ORANGE (1575 3275);
DISPLAY INVISIBLE (1575 3275);
FORCEPROP 2 LAST $SEC 1
J 0
(1575 3275);
DISPLAY 0.680851 (1575 3275);
PAINT MONO (1575 3275);
DISPLAY INVISIBLE (1575 3275);
FORCEPROP 1 LAST PATH I25
J 0
(1575 3225);
DISPLAY 0.978723 (1575 3225);
PAINT WHITE (1575 3225);
DISPLAY INVISIBLE (1575 3225);
FORCEPROP 2 LAST ROOM VDDQ_KLM_PWR_VR
J 0
(1575 3225);
DISPLAY 1.361702 (1575 3225);
PAINT ORANGE (1575 3225);
DISPLAY INVISIBLE (1575 3225);
FORCEPROP 2 LAST CDS_LIB dev_discrete
J 0
(1525 3075);
PAINT ORANGE (1525 3075);
DISPLAY INVISIBLE (1525 3075);
FORCEPROP 1 LASTPIN (1525 3175) $PN 1
J 0
(1535 3155);
DISPLAY 0.787234 (1535 3155);
PAINT ORANGE (1535 3155);
DISPLAY INVISIBLE (1535 3155);
FORCEPROP 1 LASTPIN (1525 2975) $PN 2
J 0
(1535 2955);
DISPLAY 0.787234 (1535 2955);
PAINT ORANGE (1535 2955);
DISPLAY INVISIBLE (1535 2955);
FORCEADD GND..1
(1525 2875);
FORCEPROP 3 LASTPIN (1525 2925) SIG_NAME GND\g
J 0
(1535 2935);
DISPLAY 0.659574 (1535 2935);
PAINT MONO (1535 2935);
DISPLAY INVISIBLE (1535 2935);
FORCEPROP 1 LAST HDL_POWER GND
J 0
(1525 3025);
DISPLAY 1.170213 (1525 3025);
PAINT GREEN (1525 3025);
DISPLAY INVISIBLE (1525 3025);
FORCEPROP 1 LAST BODY_TYPE PLUMBING
J 0
(1480 2832);
DISPLAY 0.340426 (1480 2832);
PAINT GREEN (1480 2832);
DISPLAY INVISIBLE (1480 2832);
FORCEPROP 1 LAST SIZE 1B
J 0
(1600 2825);
DISPLAY 1.170213 (1600 2825);
PAINT AQUA (1600 2825);
DISPLAY INVISIBLE (1600 2825);
FORCEPROP 1 LAST PATH I26
J 0
(1600 2875);
DISPLAY 0.872340 (1600 2875);
PAINT AQUA (1600 2875);
DISPLAY INVISIBLE (1600 2875);
FORCEPROP 1 LAST VOLTAGE 0
J 0
(1525 2875);
PAINT SKYBLUE (1525 2875);
DISPLAY INVISIBLE (1525 2875);
FORCEPROP 2 LAST CDS_LIB mstr_symbols
J 0
(1525 2875);
PAINT ORANGE (1525 2875);
DISPLAY INVISIBLE (1525 2875);
FORCEPROP 2 LAST ROOM VDDQ_KLM_PWR_VR
J 0
(950 2950);
DISPLAY 1.361702 (950 2950);
PAINT ORANGE (950 2950);
DISPLAY INVISIBLE (950 2950);
FORCEADD CAP_A..1
(1125 3075);
FORCEPROP 1 LAST LOCATION C1B5
J 0
(1175 3175);
DISPLAY 0.617021 (1175 3175);
PAINT AQUA (1175 3175);
FORCEPROP 1 LAST VALUE 0.1UF
J 0
(1175 3125);
DISPLAY 0.617021 (1175 3125);
PAINT SKYBLUE (1175 3125);
FORCEPROP 1 LAST VOLTAGE 16V
J 0
(1175 3075);
DISPLAY 0.617021 (1175 3075);
PAINT SKYBLUE (1175 3075);
FORCEPROP 1 LASTPIN (1125 3175) $PN 1
J 0
(1135 3155);
DISPLAY 0.617021 (1135 3155);
PAINT ORANGE (1135 3155);
FORCEPROP 1 LAST PART_NUMBER A36096-030
J 0
(1175 2925);
DISPLAY 0.617021 (1175 2925);
PAINT BLUE (1175 2925);
FORCEPROP 1 LAST PACK_TYPE 0402V
J 0
(1175 2875);
DISPLAY 0.617021 (1175 2875);
PAINT SKYBLUE (1175 2875);
FORCEPROP 1 LAST TOLERANCE 10%
J 0
(1175 3025);
DISPLAY 0.617021 (1175 3025);
PAINT SKYBLUE (1175 3025);
FORCEPROP 1 LAST MATERIAL X7R
J 0
(1175 2975);
DISPLAY 0.617021 (1175 2975);
PAINT SKYBLUE (1175 2975);
FORCEPROP 1 LASTPIN (1125 2975) $PN 2
J 0
(1135 2955);
DISPLAY 0.617021 (1135 2955);
PAINT ORANGE (1135 2955);
FORCEPROP 2 LAST SEC_TYPE 0402V
J 0
(1175 3300);
DISPLAY 1.021277 (1175 3300);
PAINT ORANGE (1175 3300);
DISPLAY INVISIBLE (1175 3300);
FORCEPROP 2 LAST SEC 1
J 0
(1175 3300);
DISPLAY 0.680851 (1175 3300);
PAINT MONO (1175 3300);
DISPLAY INVISIBLE (1175 3300);
FORCEPROP 2 LAST CDS_LOCATION C1B5
J 0
(1175 3175);
DISPLAY 0.617021 (1175 3175);
PAINT AQUA (1175 3175);
DISPLAY INVISIBLE (1175 3175);
FORCEPROP 2 LAST ROOM VDDQ_KLM_PWR_VR
J 0
(1175 3225);
DISPLAY 1.361702 (1175 3225);
PAINT ORANGE (1175 3225);
DISPLAY INVISIBLE (1175 3225);
FORCEPROP 1 LAST PATH I27
J 0
(1175 3225);
DISPLAY 0.978723 (1175 3225);
PAINT WHITE (1175 3225);
DISPLAY INVISIBLE (1175 3225);
FORCEPROP 2 LAST CDS_SEC 1
J 0
(1175 3225);
PAINT ORANGE (1175 3225);
DISPLAY INVISIBLE (1175 3225);
FORCEPROP 2 LAST CDS_LIB dev_discrete
J 0
(1125 3075);
PAINT ORANGE (1125 3075);
DISPLAY INVISIBLE (1125 3075);
FORCEADD GND..1
(1125 2875);
FORCEPROP 3 LASTPIN (1125 2925) SIG_NAME GND\g
J 0
(1135 2935);
DISPLAY 0.659574 (1135 2935);
PAINT MONO (1135 2935);
DISPLAY INVISIBLE (1135 2935);
FORCEPROP 1 LAST HDL_POWER GND
J 0
(1125 3025);
DISPLAY 1.170213 (1125 3025);
PAINT GREEN (1125 3025);
DISPLAY INVISIBLE (1125 3025);
FORCEPROP 1 LAST BODY_TYPE PLUMBING
J 0
(1080 2832);
DISPLAY 0.340426 (1080 2832);
PAINT GREEN (1080 2832);
DISPLAY INVISIBLE (1080 2832);
FORCEPROP 1 LAST PATH I28
J 0
(1200 2875);
DISPLAY 0.872340 (1200 2875);
PAINT AQUA (1200 2875);
DISPLAY INVISIBLE (1200 2875);
FORCEPROP 1 LAST SIZE 1B
J 0
(1200 2825);
DISPLAY 1.170213 (1200 2825);
PAINT AQUA (1200 2825);
DISPLAY INVISIBLE (1200 2825);
FORCEPROP 2 LAST CDS_LIB mstr_symbols
J 0
(1125 2875);
PAINT ORANGE (1125 2875);
DISPLAY INVISIBLE (1125 2875);
FORCEPROP 1 LAST VOLTAGE 0
J 0
(1125 2875);
PAINT SKYBLUE (1125 2875);
DISPLAY INVISIBLE (1125 2875);
FORCEPROP 2 LAST ROOM VDDQ_KLM_PWR_VR
J 0
(550 2950);
DISPLAY 1.361702 (550 2950);
PAINT ORANGE (550 2950);
DISPLAY INVISIBLE (550 2950);
FORCEADD P3V3_STBY..1
(500 3950);
FORCEPROP 3 LASTPIN (500 3900) SIG_NAME P3V3_STBY\g
J 0
(510 3910);
DISPLAY 0.659574 (510 3910);
PAINT MONO (510 3910);
DISPLAY INVISIBLE (510 3910);
FORCEPROP 1 LAST HDL_POWER P3V3_STBY
J 0
(200 3825);
DISPLAY 0.872340 (200 3825);
PAINT ORANGE (200 3825);
DISPLAY INVISIBLE (200 3825);
FORCEPROP 1 LAST BODY_TYPE PLUMBING
J 0
(455 3907);
DISPLAY 0.340426 (455 3907);
PAINT GREEN (455 3907);
DISPLAY INVISIBLE (455 3907);
FORCEPROP 1 LAST SIZE 1B
J 0
(545 3972);
DISPLAY 0.340426 (545 3972);
PAINT GREEN (545 3972);
DISPLAY INVISIBLE (545 3972);
FORCEPROP 1 LAST PATH I29
J 0
(545 3952);
DISPLAY 0.340426 (545 3952);
PAINT GREEN (545 3952);
DISPLAY INVISIBLE (545 3952);
FORCEPROP 1 LAST VOLTAGE 3.3V
J 0
(455 3907);
DISPLAY 0.340426 (455 3907);
PAINT SKYBLUE (455 3907);
DISPLAY INVISIBLE (455 3907);
FORCEPROP 2 LAST CDS_LIB mstr_symbols
J 0
(500 3950);
PAINT ORANGE (500 3950);
DISPLAY INVISIBLE (500 3950);
FORCEADD RES..2
(825 3525);
FORCEPROP 1 LAST PART_NUMBER G21497-005
J 0
(865 3400);
DISPLAY 0.617021 (865 3400);
PAINT BLUE (865 3400);
FORCEPROP 1 LAST VALUE 0.0
J 0
(870 3600);
DISPLAY 0.617021 (870 3600);
PAINT SKYBLUE (870 3600);
FORCEPROP 1 LAST LOCATION R9M3
J 0
(870 3650);
DISPLAY 0.617021 (870 3650);
PAINT AQUA (870 3650);
FORCEPROP 1 LASTPIN (825 3625) $PN 1
J 0
(830 3587);
DISPLAY 0.617021 (830 3587);
PAINT ORANGE (830 3587);
FORCEPROP 1 LAST WATTAGE 1/16W
J 0
(865 3500);
DISPLAY 0.617021 (865 3500);
PAINT SKYBLUE (865 3500);
FORCEPROP 1 LAST MATERIAL CHIP
J 0
(865 3450);
DISPLAY 0.617021 (865 3450);
PAINT SKYBLUE (865 3450);
FORCEPROP 1 LAST PACK_TYPE 0402
J 0
(865 3350);
DISPLAY 0.617021 (865 3350);
PAINT SKYBLUE (865 3350);
FORCEPROP 1 LAST TOLERANCE 5%
J 0
(870 3550);
DISPLAY 0.617021 (870 3550);
PAINT SKYBLUE (870 3550);
FORCEPROP 1 LASTPIN (825 3425) $PN 2
J 0
(830 3435);
DISPLAY 0.617021 (830 3435);
PAINT ORANGE (830 3435);
FORCEPROP 2 LAST SEC 1
J 0
(875 3775);
DISPLAY 0.680851 (875 3775);
PAINT MONO (875 3775);
DISPLAY INVISIBLE (875 3775);
FORCEPROP 2 LAST SEC_TYPE 0402
J 0
(875 3775);
DISPLAY 1.021277 (875 3775);
PAINT ORANGE (875 3775);
DISPLAY INVISIBLE (875 3775);
FORCEPROP 2 LAST CDS_LOCATION R9M3
J 0
(870 3650);
DISPLAY 0.617021 (870 3650);
PAINT AQUA (870 3650);
DISPLAY INVISIBLE (870 3650);
FORCEPROP 1 LAST PATH I30
J 0
(875 3700);
DISPLAY 0.978723 (875 3700);
PAINT WHITE (875 3700);
DISPLAY INVISIBLE (875 3700);
FORCEPROP 2 LAST ROOM VDDQ_KLM_PWR_VR
J 0
(875 3700);
DISPLAY 1.361702 (875 3700);
PAINT ORANGE (875 3700);
DISPLAY INVISIBLE (875 3700);
FORCEPROP 2 LAST CDS_LIB mstr_discrete
J 0
(825 3525);
PAINT ORANGE (825 3525);
DISPLAY INVISIBLE (825 3525);
FORCEADD RES..1
(-1675 1175);
FORCEPROP 1 LAST WATTAGE 1/16W
J 2
(-1675 1025);
DISPLAY 0.617021 (-1675 1025);
PAINT SKYBLUE (-1675 1025);
FORCEPROP 1 LAST VALUE 10.0
J 2
(-1775 1075);
DISPLAY 0.617021 (-1775 1075);
PAINT SKYBLUE (-1775 1075);
FORCEPROP 1 LASTPIN (-1775 1175) $PN 1
J 0
(-1763 1187);
DISPLAY 0.617021 (-1763 1187);
PAINT ORANGE (-1763 1187);
FORCEPROP 1 LAST TOLERANCE 1%
J 0
(-1750 1075);
DISPLAY 0.617021 (-1750 1075);
PAINT SKYBLUE (-1750 1075);
FORCEPROP 1 LAST LOCATION R1B16
J 0
(-1725 1225);
DISPLAY 0.617021 (-1725 1225);
PAINT AQUA (-1725 1225);
FORCEPROP 1 LASTPIN (-1575 1175) $PN 2
J 0
(-1613 1187);
DISPLAY 0.617021 (-1613 1187);
PAINT ORANGE (-1613 1187);
FORCEPROP 1 LAST MATERIAL CHIP
J 0
(-1650 1025);
DISPLAY 0.617021 (-1650 1025);
PAINT SKYBLUE (-1650 1025);
FORCEPROP 1 LAST PACK_TYPE 0402
J 0
(-1650 1075);
DISPLAY 0.617021 (-1650 1075);
PAINT SKYBLUE (-1650 1075);
FORCEPROP 1 LAST PART_NUMBER G21796-066
J 0
(-1825 1125);
DISPLAY 0.617021 (-1825 1125);
PAINT BLUE (-1825 1125);
FORCEPROP 2 LAST CDS_LIB mstr_discrete
J 0
(-1675 1175);
PAINT ORANGE (-1675 1175);
DISPLAY INVISIBLE (-1675 1175);
FORCEPROP 2 LAST CDS_LOCATION R1B16
J 0
(-1725 1225);
DISPLAY 0.617021 (-1725 1225);
PAINT AQUA (-1725 1225);
DISPLAY INVISIBLE (-1725 1225);
FORCEPROP 2 LAST ROOM VDDQ_KLM_PWR_VR
J 0
(-1600 1275);
DISPLAY 1.361702 (-1600 1275);
PAINT ORANGE (-1600 1275);
DISPLAY INVISIBLE (-1600 1275);
FORCEPROP 2 LAST SEC_TYPE 0402
J 0
(-1725 1400);
DISPLAY 1.021277 (-1725 1400);
PAINT ORANGE (-1725 1400);
DISPLAY INVISIBLE (-1725 1400);
FORCEPROP 2 LAST SEC 1
J 0
(-1725 1400);
DISPLAY 0.680851 (-1725 1400);
PAINT MONO (-1725 1400);
DISPLAY INVISIBLE (-1725 1400);
FORCEPROP 2 LAST NO_XNET_CONNECTION 1
J 0
(-1725 1375);
PAINT MONO (-1725 1375);
DISPLAY INVISIBLE (-1725 1375);
FORCEPROP 1 LAST PATH I32
J 0
(-1725 1325);
DISPLAY 0.978723 (-1725 1325);
PAINT WHITE (-1725 1325);
DISPLAY INVISIBLE (-1725 1325);
FORCEADD OFFPAGE..1
(-2250 1175);
FORCEPROP 2 LAST $XR0 228 
J 0
(-2502 1175);
DISPLAY 0.638298 (-2502 1175);
PAINT MONO (-2502 1175);
FORCEPROP 1 LAST COMMENT_BODY TRUE
J 0
(-2125 1075);
DISPLAY 1.170213 (-2125 1075);
PAINT GREEN (-2125 1075);
DISPLAY INVISIBLE (-2125 1075);
FORCEPROP 1 LAST OFFPAGE TRUE
J 0
(-1925 1050);
DISPLAY 1.170213 (-1925 1050);
PAINT GREEN (-1925 1050);
DISPLAY INVISIBLE (-1925 1050);
FORCEPROP 2 LAST CDS_LIB mstr_standard
J 0
(-2250 1175);
PAINT ORANGE (-2250 1175);
DISPLAY INVISIBLE (-2250 1175);
FORCEPROP 2 LAST PATH I34
J 0
(-2525 1225);
DISPLAY 1.021277 (-2525 1225);
PAINT ORANGE (-2525 1225);
DISPLAY INVISIBLE (-2525 1225);
FORCEPROP 2 LAST ROOM VDDQ_KLM_PWR_VR
J 0
(-2800 1250);
DISPLAY 1.361702 (-2800 1250);
PAINT ORANGE (-2800 1250);
DISPLAY INVISIBLE (-2800 1250);
FORCEADD GND..1
(100 825);
FORCEPROP 3 LASTPIN (100 875) SIG_NAME GND\g
J 0
(110 885);
DISPLAY 0.659574 (110 885);
PAINT MONO (110 885);
DISPLAY INVISIBLE (110 885);
FORCEPROP 1 LAST HDL_POWER GND
J 0
(100 975);
DISPLAY 1.170213 (100 975);
PAINT GREEN (100 975);
DISPLAY INVISIBLE (100 975);
FORCEPROP 1 LAST BODY_TYPE PLUMBING
J 0
(55 782);
DISPLAY 0.340426 (55 782);
PAINT GREEN (55 782);
DISPLAY INVISIBLE (55 782);
FORCEPROP 1 LAST PATH I35
J 0
(175 825);
DISPLAY 0.872340 (175 825);
PAINT AQUA (175 825);
DISPLAY INVISIBLE (175 825);
FORCEPROP 1 LAST SIZE 1B
J 0
(175 775);
DISPLAY 1.170213 (175 775);
PAINT AQUA (175 775);
DISPLAY INVISIBLE (175 775);
FORCEPROP 2 LAST CDS_LIB mstr_symbols
J 0
(100 825);
PAINT ORANGE (100 825);
DISPLAY INVISIBLE (100 825);
FORCEPROP 1 LAST VOLTAGE 0
J 0
(100 825);
PAINT SKYBLUE (100 825);
DISPLAY INVISIBLE (100 825);
FORCEPROP 2 LAST ROOM VDDQ_KLM_PWR_VR
J 0
(-475 900);
DISPLAY 1.361702 (-475 900);
PAINT ORANGE (-475 900);
DISPLAY INVISIBLE (-475 900);
FORCEADD CAP..1
R 2
(25 725);
FORCEPROP 1 LASTPIN (25 625) $PN 2
J 2
(15 605);
DISPLAY 0.617021 (15 605);
PAINT ORANGE (15 605);
FORCEPROP 1 LASTPIN (25 825) $PN 1
J 2
(15 805);
DISPLAY 0.617021 (15 805);
PAINT ORANGE (15 805);
FORCEPROP 1 LAST MATERIAL X7R
J 2
(-150 725);
DISPLAY 0.617021 (-150 725);
PAINT SKYBLUE (-150 725);
FORCEPROP 1 LAST VOLTAGE 50V
J 2
(-25 725);
DISPLAY 0.617021 (-25 725);
PAINT SKYBLUE (-25 725);
FORCEPROP 1 LAST PACK_TYPE 0402LF
J 2
(-25 625);
DISPLAY 0.617021 (-25 625);
PAINT SKYBLUE (-25 625);
FORCEPROP 1 LAST VALUE 220PF
J 2
(-25 775);
DISPLAY 0.617021 (-25 775);
PAINT SKYBLUE (-25 775);
FORCEPROP 1 LAST LOCATION C1B11
J 2
(-25 825);
DISPLAY 0.617021 (-25 825);
PAINT AQUA (-25 825);
FORCEPROP 1 LAST PART_NUMBER A36096-050
J 2
(-25 675);
DISPLAY 0.617021 (-25 675);
PAINT BLUE (-25 675);
FORCEPROP 1 LAST TOLERANCE 10%
J 2
(-200 775);
DISPLAY 0.617021 (-200 775);
PAINT SKYBLUE (-200 775);
FORCEPROP 2 LAST CDS_LIB mstr_discrete
J 2
(25 725);
PAINT ORANGE (25 725);
DISPLAY INVISIBLE (25 725);
FORCEPROP 2 LAST ROOM VDDQ_KLM_PWR_VR
J 2
(-25 875);
DISPLAY 1.361702 (-25 875);
PAINT ORANGE (-25 875);
DISPLAY INVISIBLE (-25 875);
FORCEPROP 1 LAST PATH I36
J 2
(-25 875);
DISPLAY 0.978723 (-25 875);
PAINT WHITE (-25 875);
DISPLAY INVISIBLE (-25 875);
FORCEPROP 2 LAST CDS_LOCATION C1B11
J 2
(-25 825);
DISPLAY 0.617021 (-25 825);
PAINT AQUA (-25 825);
DISPLAY INVISIBLE (-25 825);
FORCEPROP 2 LAST SEC 1
J 2
(-25 950);
DISPLAY 0.680851 (-25 950);
PAINT MONO (-25 950);
DISPLAY INVISIBLE (-25 950);
FORCEPROP 2 LAST SEC_TYPE 0402LF
J 2
(-25 950);
DISPLAY 1.021277 (-25 950);
PAINT ORANGE (-25 950);
DISPLAY INVISIBLE (-25 950);
FORCEADD CAP..1
(-1500 1025);
FORCEPROP 1 LAST TOLERANCE 10%
J 0
(-1275 1075);
DISPLAY 0.617021 (-1275 1075);
PAINT SKYBLUE (-1275 1075);
FORCEPROP 1 LAST MATERIAL X7R
J 0
(-1325 1025);
DISPLAY 0.617021 (-1325 1025);
PAINT SKYBLUE (-1325 1025);
FORCEPROP 1 LAST VOLTAGE 50V
J 0
(-1450 1025);
DISPLAY 0.617021 (-1450 1025);
PAINT SKYBLUE (-1450 1025);
FORCEPROP 1 LAST VALUE 220PF
J 0
(-1450 1075);
DISPLAY 0.617021 (-1450 1075);
PAINT SKYBLUE (-1450 1075);
FORCEPROP 1 LAST LOCATION C1B12
J 0
(-1450 1125);
DISPLAY 0.617021 (-1450 1125);
PAINT AQUA (-1450 1125);
FORCEPROP 1 LASTPIN (-1500 1125) $PN 1
J 0
(-1490 1105);
DISPLAY 0.617021 (-1490 1105);
PAINT ORANGE (-1490 1105);
FORCEPROP 1 LAST PART_NUMBER A36096-050
J 0
(-1450 975);
DISPLAY 0.617021 (-1450 975);
PAINT BLUE (-1450 975);
FORCEPROP 1 LAST PACK_TYPE 0402LF
J 0
(-1450 925);
DISPLAY 0.617021 (-1450 925);
PAINT SKYBLUE (-1450 925);
FORCEPROP 1 LASTPIN (-1500 925) $PN 2
J 0
(-1490 905);
DISPLAY 0.617021 (-1490 905);
PAINT ORANGE (-1490 905);
FORCEPROP 2 LAST SEC_TYPE 0402LF
J 0
(-1450 1250);
DISPLAY 1.021277 (-1450 1250);
PAINT ORANGE (-1450 1250);
DISPLAY INVISIBLE (-1450 1250);
FORCEPROP 2 LAST ROOM VDDQ_KLM_PWR_VR
J 0
(-1450 1175);
DISPLAY 1.361702 (-1450 1175);
PAINT ORANGE (-1450 1175);
DISPLAY INVISIBLE (-1450 1175);
FORCEPROP 1 LAST PATH I39
J 0
(-1450 1175);
DISPLAY 0.978723 (-1450 1175);
PAINT WHITE (-1450 1175);
DISPLAY INVISIBLE (-1450 1175);
FORCEPROP 2 LAST NO_XNET_CONNECTION 1
J 0
(-1450 1225);
PAINT MONO (-1450 1225);
DISPLAY INVISIBLE (-1450 1225);
FORCEPROP 2 LAST SEC 1
J 0
(-1450 1250);
DISPLAY 0.680851 (-1450 1250);
PAINT MONO (-1450 1250);
DISPLAY INVISIBLE (-1450 1250);
FORCEPROP 2 LAST CDS_LOCATION C1B12
J 0
(-1450 1125);
DISPLAY 0.617021 (-1450 1125);
PAINT AQUA (-1450 1125);
DISPLAY INVISIBLE (-1450 1125);
FORCEPROP 2 LAST CDS_LIB mstr_discrete
J 0
(-1500 1025);
PAINT ORANGE (-1500 1025);
DISPLAY INVISIBLE (-1500 1025);
FORCEADD OFFPAGE..2
(4050 1425);
FORCEPROP 2 LAST $XR0 227 
J 0
(4239 1425);
DISPLAY 0.638298 (4239 1425);
PAINT MONO (4239 1425);
FORCEPROP 1 LAST COMMENT_BODY TRUE
J 0
(4005 1330);
DISPLAY 1.170213 (4005 1330);
PAINT GREEN (4005 1330);
DISPLAY INVISIBLE (4005 1330);
FORCEPROP 1 LAST OFFPAGE TRUE
J 0
(4375 1300);
DISPLAY 1.170213 (4375 1300);
PAINT GREEN (4375 1300);
DISPLAY INVISIBLE (4375 1300);
FORCEPROP 2 LAST PATH I4
J 0
(4225 1500);
DISPLAY 1.021277 (4225 1500);
PAINT ORANGE (4225 1500);
DISPLAY INVISIBLE (4225 1500);
FORCEPROP 2 LAST ROOM VDDQ_KLM_PWR_VR
J 0
(3625 1500);
DISPLAY 1.361702 (3625 1500);
PAINT ORANGE (3625 1500);
DISPLAY INVISIBLE (3625 1500);
FORCEPROP 2 LAST CDS_LIB mstr_standard
J 0
(4050 1425);
PAINT ORANGE (4050 1425);
DISPLAY INVISIBLE (4050 1425);
FORCEADD OFFPAGE..1
R 2
(4350 350);
FORCEPROP 2 LAST $XR0 226 
J 0
(4536 350);
DISPLAY 0.638298 (4536 350);
PAINT MONO (4536 350);
FORCEPROP 1 LAST COMMENT_BODY TRUE
J 2
(4225 250);
DISPLAY 1.170213 (4225 250);
PAINT GREEN (4225 250);
DISPLAY INVISIBLE (4225 250);
FORCEPROP 1 LAST OFFPAGE TRUE
J 2
(4025 225);
DISPLAY 1.170213 (4025 225);
PAINT GREEN (4025 225);
DISPLAY INVISIBLE (4025 225);
FORCEPROP 2 LAST PATH I40
J 0
(4550 400);
DISPLAY 1.021277 (4550 400);
PAINT ORANGE (4550 400);
DISPLAY INVISIBLE (4550 400);
FORCEPROP 2 LAST CDS_LIB mstr_standard
J 2
(4350 350);
PAINT ORANGE (4350 350);
DISPLAY INVISIBLE (4350 350);
FORCEPROP 2 LAST ROOM VDDQ_KLM_PWR_VR
J 0
(3925 425);
DISPLAY 1.361702 (3925 425);
PAINT ORANGE (3925 425);
DISPLAY INVISIBLE (3925 425);
FORCEADD CAP_A..1
(3750 150);
FORCEPROP 1 LAST LOCATION C1B3
J 0
(3800 250);
DISPLAY 0.617021 (3800 250);
PAINT AQUA (3800 250);
FORCEPROP 1 LAST VALUE 1.0UF
J 0
(3800 200);
DISPLAY 0.617021 (3800 200);
PAINT SKYBLUE (3800 200);
FORCEPROP 1 LAST TOLERANCE 10%
J 0
(3800 100);
DISPLAY 0.617021 (3800 100);
PAINT SKYBLUE (3800 100);
FORCEPROP 1 LAST VOLTAGE 6.3V
J 0
(3800 150);
DISPLAY 0.617021 (3800 150);
PAINT SKYBLUE (3800 150);
FORCEPROP 1 LAST MATERIAL X6S
J 0
(3800 50);
DISPLAY 0.617021 (3800 50);
PAINT SKYBLUE (3800 50);
FORCEPROP 1 LASTPIN (3750 50) $PN 2
J 0
(3760 30);
DISPLAY 0.617021 (3760 30);
PAINT ORANGE (3760 30);
FORCEPROP 1 LASTPIN (3750 250) $PN 1
J 0
(3760 230);
DISPLAY 0.617021 (3760 230);
PAINT ORANGE (3760 230);
FORCEPROP 1 LAST PART_NUMBER D97712-004
J 0
(3800 0);
DISPLAY 0.617021 (3800 0);
PAINT BLUE (3800 0);
FORCEPROP 1 LAST PACK_TYPE 0402V
J 0
(3800 -50);
DISPLAY 0.617021 (3800 -50);
PAINT SKYBLUE (3800 -50);
FORCEPROP 2 LAST ROOM VDDQ_KLM_PWR_VR
J 0
(3800 300);
DISPLAY 1.361702 (3800 300);
PAINT ORANGE (3800 300);
DISPLAY INVISIBLE (3800 300);
FORCEPROP 1 LAST PATH I41
J 0
(3800 300);
DISPLAY 0.978723 (3800 300);
PAINT WHITE (3800 300);
DISPLAY INVISIBLE (3800 300);
FORCEPROP 2 LAST SEC 1
J 0
(3800 350);
DISPLAY 0.680851 (3800 350);
PAINT MONO (3800 350);
DISPLAY INVISIBLE (3800 350);
FORCEPROP 2 LAST SEC_TYPE 0402V
J 0
(3800 350);
DISPLAY 1.021277 (3800 350);
PAINT ORANGE (3800 350);
DISPLAY INVISIBLE (3800 350);
FORCEPROP 2 LAST CDS_SEC 1
J 0
(3800 300);
PAINT ORANGE (3800 300);
DISPLAY INVISIBLE (3800 300);
FORCEPROP 2 LAST CDS_LOCATION C1B3
J 0
(3800 250);
DISPLAY 0.617021 (3800 250);
PAINT AQUA (3800 250);
DISPLAY INVISIBLE (3800 250);
FORCEPROP 2 LAST CDS_LIB dev_discrete
J 0
(3750 150);
PAINT ORANGE (3750 150);
DISPLAY INVISIBLE (3750 150);
FORCEADD GND..1
(3750 -175);
FORCEPROP 3 LASTPIN (3750 -125) SIG_NAME GND\g
J 0
(3760 -115);
DISPLAY 0.659574 (3760 -115);
PAINT MONO (3760 -115);
DISPLAY INVISIBLE (3760 -115);
FORCEPROP 1 LAST HDL_POWER GND
J 0
(3750 -25);
DISPLAY 1.170213 (3750 -25);
PAINT GREEN (3750 -25);
DISPLAY INVISIBLE (3750 -25);
FORCEPROP 1 LAST BODY_TYPE PLUMBING
J 0
(3705 -218);
DISPLAY 0.340426 (3705 -218);
PAINT GREEN (3705 -218);
DISPLAY INVISIBLE (3705 -218);
FORCEPROP 1 LAST VOLTAGE 0
J 0
(3750 -175);
PAINT SKYBLUE (3750 -175);
DISPLAY INVISIBLE (3750 -175);
FORCEPROP 1 LAST SIZE 1B
J 0
(3825 -225);
DISPLAY 1.170213 (3825 -225);
PAINT AQUA (3825 -225);
DISPLAY INVISIBLE (3825 -225);
FORCEPROP 2 LAST CDS_LIB mstr_symbols
J 0
(3750 -175);
PAINT ORANGE (3750 -175);
DISPLAY INVISIBLE (3750 -175);
FORCEPROP 1 LAST PATH I42
J 0
(3825 -175);
DISPLAY 0.872340 (3825 -175);
PAINT AQUA (3825 -175);
DISPLAY INVISIBLE (3825 -175);
FORCEPROP 2 LAST ROOM VDDQ_KLM_PWR_VR
J 0
(3175 -100);
DISPLAY 1.361702 (3175 -100);
PAINT ORANGE (3175 -100);
DISPLAY INVISIBLE (3175 -100);
FORCEADD GND..1
(3350 -25);
FORCEPROP 3 LASTPIN (3350 25) SIG_NAME GND\g
J 0
(3360 35);
DISPLAY 0.659574 (3360 35);
PAINT MONO (3360 35);
DISPLAY INVISIBLE (3360 35);
FORCEPROP 1 LAST HDL_POWER GND
J 0
(3350 125);
DISPLAY 1.170213 (3350 125);
PAINT GREEN (3350 125);
DISPLAY INVISIBLE (3350 125);
FORCEPROP 1 LAST BODY_TYPE PLUMBING
J 0
(3305 -68);
DISPLAY 0.340426 (3305 -68);
PAINT GREEN (3305 -68);
DISPLAY INVISIBLE (3305 -68);
FORCEPROP 2 LAST ROOM VDDQ_KLM_PWR_VR
J 0
(2775 50);
DISPLAY 1.361702 (2775 50);
PAINT ORANGE (2775 50);
DISPLAY INVISIBLE (2775 50);
FORCEPROP 1 LAST VOLTAGE 0
J 0
(3350 -25);
PAINT SKYBLUE (3350 -25);
DISPLAY INVISIBLE (3350 -25);
FORCEPROP 2 LAST CDS_LIB mstr_symbols
J 0
(3350 -25);
PAINT ORANGE (3350 -25);
DISPLAY INVISIBLE (3350 -25);
FORCEPROP 1 LAST PATH I43
J 0
(3425 -25);
DISPLAY 0.872340 (3425 -25);
PAINT AQUA (3425 -25);
DISPLAY INVISIBLE (3425 -25);
FORCEPROP 1 LAST SIZE 1B
J 0
(3425 -75);
DISPLAY 1.170213 (3425 -75);
PAINT AQUA (3425 -75);
DISPLAY INVISIBLE (3425 -75);
FORCEADD CAP_A..1
(3350 175);
FORCEPROP 1 LAST PART_NUMBER A36096-030
J 0
(3400 25);
DISPLAY 0.617021 (3400 25);
PAINT BLUE (3400 25);
FORCEPROP 1 LAST LOCATION C1B2
J 0
(3400 275);
DISPLAY 0.617021 (3400 275);
PAINT AQUA (3400 275);
FORCEPROP 1 LASTPIN (3350 275) $PN 1
J 0
(3360 255);
DISPLAY 0.617021 (3360 255);
PAINT ORANGE (3360 255);
FORCEPROP 1 LAST VALUE 0.1UF
J 0
(3400 225);
DISPLAY 0.617021 (3400 225);
PAINT SKYBLUE (3400 225);
FORCEPROP 1 LAST TOLERANCE 10%
J 0
(3400 125);
DISPLAY 0.617021 (3400 125);
PAINT SKYBLUE (3400 125);
FORCEPROP 1 LAST VOLTAGE 16V
J 0
(3400 175);
DISPLAY 0.617021 (3400 175);
PAINT SKYBLUE (3400 175);
FORCEPROP 1 LAST MATERIAL X7R
J 0
(3400 75);
DISPLAY 0.617021 (3400 75);
PAINT SKYBLUE (3400 75);
FORCEPROP 1 LASTPIN (3350 75) $PN 2
J 0
(3360 55);
DISPLAY 0.617021 (3360 55);
PAINT ORANGE (3360 55);
FORCEPROP 1 LAST PACK_TYPE 0402V
J 0
(3400 -25);
DISPLAY 0.617021 (3400 -25);
PAINT SKYBLUE (3400 -25);
FORCEPROP 2 LAST SEC 1
J 0
(3400 400);
DISPLAY 0.680851 (3400 400);
PAINT MONO (3400 400);
DISPLAY INVISIBLE (3400 400);
FORCEPROP 2 LAST SEC_TYPE 0402V
J 0
(3400 400);
DISPLAY 1.021277 (3400 400);
PAINT ORANGE (3400 400);
DISPLAY INVISIBLE (3400 400);
FORCEPROP 2 LAST CDS_SEC 1
J 0
(3400 325);
PAINT ORANGE (3400 325);
DISPLAY INVISIBLE (3400 325);
FORCEPROP 2 LAST CDS_LOCATION C1B2
J 0
(3400 275);
DISPLAY 0.617021 (3400 275);
PAINT AQUA (3400 275);
DISPLAY INVISIBLE (3400 275);
FORCEPROP 1 LAST PATH I44
J 0
(3400 325);
DISPLAY 0.978723 (3400 325);
PAINT WHITE (3400 325);
DISPLAY INVISIBLE (3400 325);
FORCEPROP 2 LAST ROOM VDDQ_KLM_PWR_VR
J 0
(3400 325);
DISPLAY 1.361702 (3400 325);
PAINT ORANGE (3400 325);
DISPLAY INVISIBLE (3400 325);
FORCEPROP 2 LAST CDS_LIB dev_discrete
J 0
(3350 175);
PAINT ORANGE (3350 175);
DISPLAY INVISIBLE (3350 175);
FORCEADD OFFPAGE..1
(-2225 900);
FORCEPROP 2 LAST $XR0 228 
J 0
(-2507 900);
DISPLAY 0.638298 (-2507 900);
PAINT MONO (-2507 900);
FORCEPROP 1 LAST COMMENT_BODY TRUE
J 0
(-2100 800);
DISPLAY 1.170213 (-2100 800);
PAINT GREEN (-2100 800);
DISPLAY INVISIBLE (-2100 800);
FORCEPROP 1 LAST OFFPAGE TRUE
J 0
(-1900 775);
DISPLAY 1.170213 (-1900 775);
PAINT GREEN (-1900 775);
DISPLAY INVISIBLE (-1900 775);
FORCEPROP 2 LAST ROOM VDDQ_KLM_PWR_VR
J 0
(-2775 975);
DISPLAY 1.361702 (-2775 975);
PAINT ORANGE (-2775 975);
DISPLAY INVISIBLE (-2775 975);
FORCEPROP 2 LAST CDS_LIB mstr_standard
J 0
(-2225 900);
PAINT ORANGE (-2225 900);
DISPLAY INVISIBLE (-2225 900);
FORCEPROP 2 LAST PATH I45
J 0
(-2500 950);
DISPLAY 1.021277 (-2500 950);
PAINT ORANGE (-2500 950);
DISPLAY INVISIBLE (-2500 950);
FORCEADD GND..1
(575 25);
FORCEPROP 3 LASTPIN (575 75) SIG_NAME GND\g
J 0
(585 85);
DISPLAY 0.659574 (585 85);
PAINT MONO (585 85);
DISPLAY INVISIBLE (585 85);
FORCEPROP 1 LAST HDL_POWER GND
J 0
(575 175);
DISPLAY 1.170213 (575 175);
PAINT GREEN (575 175);
DISPLAY INVISIBLE (575 175);
FORCEPROP 1 LAST BODY_TYPE PLUMBING
J 0
(530 -18);
DISPLAY 0.340426 (530 -18);
PAINT GREEN (530 -18);
DISPLAY INVISIBLE (530 -18);
FORCEPROP 1 LAST PATH I46
J 0
(650 25);
DISPLAY 0.872340 (650 25);
PAINT AQUA (650 25);
DISPLAY INVISIBLE (650 25);
FORCEPROP 2 LAST CDS_LIB mstr_symbols
J 0
(575 25);
PAINT ORANGE (575 25);
DISPLAY INVISIBLE (575 25);
FORCEPROP 1 LAST VOLTAGE 0
J 0
(575 25);
PAINT SKYBLUE (575 25);
DISPLAY INVISIBLE (575 25);
FORCEPROP 1 LAST SIZE 1B
J 0
(650 -25);
DISPLAY 1.170213 (650 -25);
PAINT AQUA (650 -25);
DISPLAY INVISIBLE (650 -25);
FORCEPROP 2 LAST ROOM VDDQ_KLM_PWR_VR
J 0
(0 100);
DISPLAY 1.361702 (0 100);
PAINT ORANGE (0 100);
DISPLAY INVISIBLE (0 100);
FORCEADD GND..1
(200 25);
FORCEPROP 3 LASTPIN (200 75) SIG_NAME GND\g
J 0
(210 85);
DISPLAY 0.659574 (210 85);
PAINT MONO (210 85);
DISPLAY INVISIBLE (210 85);
FORCEPROP 1 LAST HDL_POWER GND
J 0
(200 175);
DISPLAY 1.170213 (200 175);
PAINT GREEN (200 175);
DISPLAY INVISIBLE (200 175);
FORCEPROP 1 LAST BODY_TYPE PLUMBING
J 0
(155 -18);
DISPLAY 0.340426 (155 -18);
PAINT GREEN (155 -18);
DISPLAY INVISIBLE (155 -18);
FORCEPROP 1 LAST PATH I47
J 0
(275 25);
DISPLAY 0.872340 (275 25);
PAINT AQUA (275 25);
DISPLAY INVISIBLE (275 25);
FORCEPROP 2 LAST CDS_LIB mstr_symbols
J 0
(200 25);
PAINT ORANGE (200 25);
DISPLAY INVISIBLE (200 25);
FORCEPROP 1 LAST VOLTAGE 0
J 0
(200 25);
PAINT SKYBLUE (200 25);
DISPLAY INVISIBLE (200 25);
FORCEPROP 1 LAST SIZE 1B
J 0
(275 -25);
DISPLAY 1.170213 (275 -25);
PAINT AQUA (275 -25);
DISPLAY INVISIBLE (275 -25);
FORCEPROP 2 LAST ROOM VDDQ_KLM_PWR_VR
J 0
(-375 100);
DISPLAY 1.361702 (-375 100);
PAINT ORANGE (-375 100);
DISPLAY INVISIBLE (-375 100);
FORCEADD GND..1
(25 25);
FORCEPROP 3 LASTPIN (25 75) SIG_NAME GND\g
J 0
(35 85);
DISPLAY 0.659574 (35 85);
PAINT MONO (35 85);
DISPLAY INVISIBLE (35 85);
FORCEPROP 1 LAST HDL_POWER GND
J 0
(25 175);
DISPLAY 1.170213 (25 175);
PAINT GREEN (25 175);
DISPLAY INVISIBLE (25 175);
FORCEPROP 1 LAST BODY_TYPE PLUMBING
J 0
(-20 -18);
DISPLAY 0.340426 (-20 -18);
PAINT GREEN (-20 -18);
DISPLAY INVISIBLE (-20 -18);
FORCEPROP 1 LAST VOLTAGE 0
J 0
(25 25);
PAINT SKYBLUE (25 25);
DISPLAY INVISIBLE (25 25);
FORCEPROP 2 LAST CDS_LIB mstr_symbols
J 0
(25 25);
PAINT ORANGE (25 25);
DISPLAY INVISIBLE (25 25);
FORCEPROP 1 LAST PATH I48
J 0
(100 25);
DISPLAY 0.872340 (100 25);
PAINT AQUA (100 25);
DISPLAY INVISIBLE (100 25);
FORCEPROP 1 LAST SIZE 1B
J 0
(100 -25);
DISPLAY 1.170213 (100 -25);
PAINT AQUA (100 -25);
DISPLAY INVISIBLE (100 -25);
FORCEPROP 2 LAST ROOM VDDQ_KLM_PWR_VR
J 0
(-550 100);
DISPLAY 1.361702 (-550 100);
PAINT ORANGE (-550 100);
DISPLAY INVISIBLE (-550 100);
FORCEADD PVCCIO_CPU1..1
(-675 3900);
FORCEPROP 3 LASTPIN (-675 3850) SIG_NAME PVCCIO_CPU1\g
J 0
(-665 3860);
DISPLAY 0.659574 (-665 3860);
PAINT MONO (-665 3860);
DISPLAY INVISIBLE (-665 3860);
FORCEPROP 1 LAST HDL_POWER PVCCIO_CPU1
J 1
(-675 3950);
DISPLAY 0.872340 (-675 3950);
PAINT GREEN (-675 3950);
DISPLAY INVISIBLE (-675 3950);
FORCEPROP 1 LAST BODY_TYPE PLUMBING
J 0
(-720 3857);
DISPLAY 0.340426 (-720 3857);
PAINT GREEN (-720 3857);
DISPLAY INVISIBLE (-720 3857);
FORCEPROP 1 LAST VOLTAGE 1.1V
J 0
(-720 3857);
DISPLAY 0.340426 (-720 3857);
PAINT SKYBLUE (-720 3857);
DISPLAY INVISIBLE (-720 3857);
FORCEPROP 2 LAST CDS_LIB mstr_symbols
J 0
(-675 3900);
PAINT ORANGE (-675 3900);
DISPLAY INVISIBLE (-675 3900);
FORCEPROP 1 LAST PATH I49
J 0
(-625 3925);
DISPLAY 0.872340 (-625 3925);
PAINT AQUA (-625 3925);
DISPLAY INVISIBLE (-625 3925);
FORCEADD RES..2
(-675 3550);
FORCEPROP 1 LAST PART_NUMBER G21796-047
J 0
(-635 3425);
DISPLAY 0.617021 (-635 3425);
PAINT BLUE (-635 3425);
FORCEPROP 1 LAST WATTAGE 1/16W
J 0
(-635 3525);
DISPLAY 0.617021 (-635 3525);
PAINT SKYBLUE (-635 3525);
FORCEPROP 1 LAST LOCATION R9M6
J 0
(-630 3675);
DISPLAY 0.617021 (-630 3675);
PAINT AQUA (-630 3675);
FORCEPROP 1 LAST VALUE 49.9
J 0
(-630 3625);
DISPLAY 0.617021 (-630 3625);
PAINT SKYBLUE (-630 3625);
FORCEPROP 1 LASTPIN (-675 3650) $PN 1
J 0
(-670 3612);
DISPLAY 0.617021 (-670 3612);
PAINT ORANGE (-670 3612);
FORCEPROP 1 LAST TOLERANCE 1%
J 0
(-630 3575);
DISPLAY 0.617021 (-630 3575);
PAINT SKYBLUE (-630 3575);
FORCEPROP 1 LAST PACK_TYPE 0402
J 0
(-635 3375);
DISPLAY 0.617021 (-635 3375);
PAINT SKYBLUE (-635 3375);
FORCEPROP 1 LASTPIN (-675 3450) $PN 2
J 0
(-670 3460);
DISPLAY 0.617021 (-670 3460);
PAINT ORANGE (-670 3460);
FORCEPROP 2 LAST SEC_TYPE 0402
J 0
(-625 3800);
DISPLAY 1.021277 (-625 3800);
PAINT ORANGE (-625 3800);
DISPLAY INVISIBLE (-625 3800);
FORCEPROP 2 LAST SEC 1
J 0
(-625 3800);
PAINT MONO (-625 3800);
DISPLAY INVISIBLE (-625 3800);
FORCEPROP 2 LAST CDS_LOCATION R9M6
J 0
(-630 3675);
DISPLAY 0.617021 (-630 3675);
PAINT AQUA (-630 3675);
DISPLAY INVISIBLE (-630 3675);
FORCEPROP 1 LAST PATH I50
J 0
(-625 3725);
DISPLAY 0.978723 (-625 3725);
PAINT WHITE (-625 3725);
DISPLAY INVISIBLE (-625 3725);
FORCEPROP 2 LAST ROOM VDDQ_KLM_PWR_VR
J 0
(-625 3725);
DISPLAY 1.361702 (-625 3725);
PAINT ORANGE (-625 3725);
DISPLAY INVISIBLE (-625 3725);
FORCEPROP 2 LAST CDS_LIB mstr_discrete
J 0
(-675 3550);
PAINT ORANGE (-675 3550);
DISPLAY INVISIBLE (-675 3550);
FORCEPROP 1 LAST MATERIAL CHIP
J 0
(-635 3475);
PAINT SKYBLUE (-635 3475);
DISPLAY INVISIBLE (-635 3475);
FORCEADD RES..1
(-300 3050);
FORCEPROP 1 LASTPIN (-400 3050) $PN 1
J 0
(-388 3062);
DISPLAY 0.617021 (-388 3062);
PAINT ORANGE (-388 3062);
FORCEPROP 1 LASTPIN (-200 3050) $PN 2
J 0
(-238 3062);
DISPLAY 0.617021 (-238 3062);
PAINT ORANGE (-238 3062);
FORCEPROP 1 LAST VALUE 150.0
J 2
(-300 3125);
DISPLAY 0.617021 (-300 3125);
PAINT SKYBLUE (-300 3125);
FORCEPROP 1 LAST LOCATION R1B8
J 0
(-400 3225);
DISPLAY 0.617021 (-400 3225);
PAINT AQUA (-400 3225);
FORCEPROP 1 LAST PART_NUMBER G21796-009
J 0
(-400 3175);
DISPLAY 0.617021 (-400 3175);
PAINT BLUE (-400 3175);
FORCEPROP 1 LAST WATTAGE 1/16W
J 2
(-250 3075);
DISPLAY 0.617021 (-250 3075);
PAINT SKYBLUE (-250 3075);
FORCEPROP 1 LAST MATERIAL CHIP
J 0
(-200 3075);
DISPLAY 0.617021 (-200 3075);
PAINT SKYBLUE (-200 3075);
FORCEPROP 1 LAST PACK_TYPE 0402
J 0
(-125 3125);
DISPLAY 0.617021 (-125 3125);
PAINT SKYBLUE (-125 3125);
FORCEPROP 1 LAST TOLERANCE 1%
J 0
(-250 3125);
DISPLAY 0.617021 (-250 3125);
PAINT SKYBLUE (-250 3125);
FORCEPROP 2 LAST CDS_LIB mstr_discrete
J 0
(-300 3050);
PAINT ORANGE (-300 3050);
DISPLAY INVISIBLE (-300 3050);
FORCEPROP 2 LAST SEC_TYPE 0402
J 0
(-350 3275);
DISPLAY 1.021277 (-350 3275);
PAINT ORANGE (-350 3275);
DISPLAY INVISIBLE (-350 3275);
FORCEPROP 2 LAST SEC 1
J 0
(-350 3275);
DISPLAY 0.680851 (-350 3275);
PAINT MONO (-350 3275);
DISPLAY INVISIBLE (-350 3275);
FORCEPROP 2 LAST ROOM VDDQ_KLM_PWR_VR
J 0
(-400 3275);
DISPLAY 1.361702 (-400 3275);
PAINT ORANGE (-400 3275);
DISPLAY INVISIBLE (-400 3275);
FORCEPROP 2 LAST CDS_LOCATION R1B8
J 0
(-400 3225);
DISPLAY 0.617021 (-400 3225);
PAINT AQUA (-400 3225);
DISPLAY INVISIBLE (-400 3225);
FORCEPROP 1 LAST PATH I53
J 0
(-350 3200);
DISPLAY 0.978723 (-350 3200);
PAINT WHITE (-350 3200);
DISPLAY INVISIBLE (-350 3200);
FORCEADD VCC_CORE..1
(-1250 3975);
FORCEPROP 3 LASTPIN (-1250 3925) SIG_NAME VR_FET_SW_P12V_STBY_PVDDQ_KLM\g
J 0
(-1240 3935);
DISPLAY 0.659574 (-1240 3935);
PAINT MONO (-1240 3935);
DISPLAY INVISIBLE (-1240 3935);
FORCEPROP 1 LAST HDL_POWER VR_FET_SW_P12V_STBY_PVDDQ_KLM
J 1
(-1525 4025);
DISPLAY 0.617021 (-1525 4025);
PAINT GREEN (-1525 4025);
FORCEPROP 2 LAST CDS_LIB mstr_symbols
J 0
(-1250 3975);
PAINT ORANGE (-1250 3975);
DISPLAY INVISIBLE (-1250 3975);
FORCEPROP 1 LAST PATH I56
J 0
(-1200 4000);
DISPLAY 0.872340 (-1200 4000);
PAINT AQUA (-1200 4000);
DISPLAY INVISIBLE (-1200 4000);
FORCEADD RES..2
(-1250 3725);
FORCEPROP 1 LAST PART_NUMBER G21796-160
J 0
(-1210 3600);
DISPLAY 0.617021 (-1210 3600);
PAINT BLUE (-1210 3600);
FORCEPROP 1 LAST LOCATION R9M8
J 0
(-1205 3850);
DISPLAY 0.617021 (-1205 3850);
PAINT AQUA (-1205 3850);
FORCEPROP 1 LAST VALUE 100.0K
J 0
(-1205 3800);
DISPLAY 0.617021 (-1205 3800);
PAINT SKYBLUE (-1205 3800);
FORCEPROP 1 LAST WATTAGE 1/16W
J 0
(-1210 3700);
DISPLAY 0.617021 (-1210 3700);
PAINT SKYBLUE (-1210 3700);
FORCEPROP 1 LAST MATERIAL CHIP
J 0
(-1210 3650);
DISPLAY 0.617021 (-1210 3650);
PAINT SKYBLUE (-1210 3650);
FORCEPROP 1 LAST TOLERANCE 1%
J 0
(-1205 3750);
DISPLAY 0.617021 (-1205 3750);
PAINT SKYBLUE (-1205 3750);
FORCEPROP 1 LASTPIN (-1250 3825) $PN 1
J 0
(-1245 3787);
DISPLAY 0.617021 (-1245 3787);
PAINT ORANGE (-1245 3787);
FORCEPROP 1 LASTPIN (-1250 3625) $PN 2
J 0
(-1245 3635);
DISPLAY 0.617021 (-1245 3635);
PAINT ORANGE (-1245 3635);
FORCEPROP 1 LAST PACK_TYPE 0402
J 0
(-1210 3550);
DISPLAY 0.617021 (-1210 3550);
PAINT SKYBLUE (-1210 3550);
FORCEPROP 2 LAST SEC_TYPE 0402
J 0
(-1200 3950);
DISPLAY 1.021277 (-1200 3950);
PAINT ORANGE (-1200 3950);
DISPLAY INVISIBLE (-1200 3950);
FORCEPROP 2 LAST SEC 1
J 0
(-1200 3950);
DISPLAY 0.680851 (-1200 3950);
PAINT MONO (-1200 3950);
DISPLAY INVISIBLE (-1200 3950);
FORCEPROP 2 LAST CDS_LOCATION R9M8
J 0
(-1205 3850);
DISPLAY 0.617021 (-1205 3850);
PAINT AQUA (-1205 3850);
DISPLAY INVISIBLE (-1205 3850);
FORCEPROP 1 LAST PATH I57
J 0
(-1200 3900);
DISPLAY 0.978723 (-1200 3900);
PAINT WHITE (-1200 3900);
DISPLAY INVISIBLE (-1200 3900);
FORCEPROP 2 LAST ROOM VDDQ_KLM_PWR_VR
J 0
(-1200 3900);
DISPLAY 1.361702 (-1200 3900);
PAINT ORANGE (-1200 3900);
DISPLAY INVISIBLE (-1200 3900);
FORCEPROP 2 LAST CDS_LIB mstr_discrete
J 0
(-1250 3725);
PAINT ORANGE (-1250 3725);
DISPLAY INVISIBLE (-1250 3725);
FORCEADD RES..2
(-1250 3325);
FORCEPROP 1 LAST PART_NUMBER G21796-003
J 0
(-1210 3200);
DISPLAY 0.617021 (-1210 3200);
PAINT BLUE (-1210 3200);
FORCEPROP 1 LAST TOLERANCE 1%
J 0
(-1205 3350);
DISPLAY 0.617021 (-1205 3350);
PAINT SKYBLUE (-1205 3350);
FORCEPROP 1 LAST VALUE 1.5K
J 0
(-1205 3400);
DISPLAY 0.617021 (-1205 3400);
PAINT SKYBLUE (-1205 3400);
FORCEPROP 1 LAST LOCATION R1B9
J 0
(-1205 3450);
DISPLAY 0.617021 (-1205 3450);
PAINT AQUA (-1205 3450);
FORCEPROP 1 LASTPIN (-1250 3425) $PN 1
J 0
(-1245 3387);
DISPLAY 0.617021 (-1245 3387);
PAINT ORANGE (-1245 3387);
FORCEPROP 1 LAST PACK_TYPE 0402
J 0
(-1210 3150);
DISPLAY 0.617021 (-1210 3150);
PAINT SKYBLUE (-1210 3150);
FORCEPROP 1 LAST MATERIAL CHIP
J 0
(-1210 3250);
DISPLAY 0.617021 (-1210 3250);
PAINT SKYBLUE (-1210 3250);
FORCEPROP 1 LAST WATTAGE 1/16W
J 0
(-1210 3300);
DISPLAY 0.617021 (-1210 3300);
PAINT SKYBLUE (-1210 3300);
FORCEPROP 1 LASTPIN (-1250 3225) $PN 2
J 0
(-1245 3235);
DISPLAY 0.617021 (-1245 3235);
PAINT ORANGE (-1245 3235);
FORCEPROP 2 LAST SEC_TYPE 0402
J 0
(-1200 3550);
DISPLAY 1.021277 (-1200 3550);
PAINT ORANGE (-1200 3550);
DISPLAY INVISIBLE (-1200 3550);
FORCEPROP 2 LAST SEC 1
J 0
(-1200 3550);
DISPLAY 0.680851 (-1200 3550);
PAINT MONO (-1200 3550);
DISPLAY INVISIBLE (-1200 3550);
FORCEPROP 1 LAST PATH I58
J 0
(-1200 3500);
DISPLAY 0.978723 (-1200 3500);
PAINT WHITE (-1200 3500);
DISPLAY INVISIBLE (-1200 3500);
FORCEPROP 2 LAST ROOM VDDQ_KLM_PWR_VR
J 0
(-1200 3500);
DISPLAY 1.361702 (-1200 3500);
PAINT ORANGE (-1200 3500);
DISPLAY INVISIBLE (-1200 3500);
FORCEPROP 2 LAST CDS_LOCATION R1B9
J 0
(-1205 3450);
DISPLAY 0.617021 (-1205 3450);
PAINT AQUA (-1205 3450);
DISPLAY INVISIBLE (-1205 3450);
FORCEPROP 2 LAST CDS_LIB mstr_discrete
J 0
(-1250 3325);
PAINT ORANGE (-1250 3325);
DISPLAY INVISIBLE (-1250 3325);
FORCEADD CAP..1
R 2
(-1475 3375);
FORCEPROP 1 LASTPIN (-1475 3475) $PN 1
J 2
(-1485 3455);
DISPLAY 0.617021 (-1485 3455);
PAINT ORANGE (-1485 3455);
FORCEPROP 1 LASTPIN (-1475 3275) $PN 2
J 2
(-1485 3255);
DISPLAY 0.617021 (-1485 3255);
PAINT ORANGE (-1485 3255);
FORCEPROP 1 LAST LOCATION C1B8
J 2
(-1525 3475);
DISPLAY 0.617021 (-1525 3475);
PAINT AQUA (-1525 3475);
FORCEPROP 1 LAST PART_NUMBER A36096-046
J 2
(-1525 3225);
DISPLAY 0.617021 (-1525 3225);
PAINT BLUE (-1525 3225);
FORCEPROP 1 LAST VALUE 1000PF
J 2
(-1525 3425);
DISPLAY 0.617021 (-1525 3425);
PAINT SKYBLUE (-1525 3425);
FORCEPROP 1 LAST TOLERANCE 10%
J 2
(-1525 3325);
DISPLAY 0.617021 (-1525 3325);
PAINT SKYBLUE (-1525 3325);
FORCEPROP 1 LAST PACK_TYPE 0402LF
J 2
(-1525 3175);
DISPLAY 0.617021 (-1525 3175);
PAINT SKYBLUE (-1525 3175);
FORCEPROP 1 LAST VOLTAGE 50V
J 2
(-1525 3375);
DISPLAY 0.617021 (-1525 3375);
PAINT SKYBLUE (-1525 3375);
FORCEPROP 1 LAST MATERIAL X7R
J 2
(-1525 3275);
DISPLAY 0.617021 (-1525 3275);
PAINT SKYBLUE (-1525 3275);
FORCEPROP 2 LAST SEC_TYPE 0402LF
J 0
(-1525 3600);
DISPLAY 1.021277 (-1525 3600);
PAINT ORANGE (-1525 3600);
DISPLAY INVISIBLE (-1525 3600);
FORCEPROP 2 LAST SEC 1
J 0
(-1525 3600);
DISPLAY 0.680851 (-1525 3600);
PAINT MONO (-1525 3600);
DISPLAY INVISIBLE (-1525 3600);
FORCEPROP 2 LAST CDS_LOCATION C1B8
J 2
(-1525 3475);
DISPLAY 0.617021 (-1525 3475);
PAINT AQUA (-1525 3475);
DISPLAY INVISIBLE (-1525 3475);
FORCEPROP 1 LAST PATH I59
J 2
(-1525 3525);
DISPLAY 0.978723 (-1525 3525);
PAINT WHITE (-1525 3525);
DISPLAY INVISIBLE (-1525 3525);
FORCEPROP 2 LAST ROOM VDDQ_KLM_PWR_VR
J 0
(-1525 3525);
DISPLAY 1.361702 (-1525 3525);
PAINT ORANGE (-1525 3525);
DISPLAY INVISIBLE (-1525 3525);
FORCEPROP 2 LAST CDS_LIB mstr_discrete
J 2
(-1475 3375);
PAINT ORANGE (-1475 3375);
DISPLAY INVISIBLE (-1475 3375);
FORCEADD GND..1
(-1250 3100);
FORCEPROP 3 LASTPIN (-1250 3150) SIG_NAME GND\g
J 0
(-1240 3160);
DISPLAY 0.659574 (-1240 3160);
PAINT MONO (-1240 3160);
DISPLAY INVISIBLE (-1240 3160);
FORCEPROP 1 LAST HDL_POWER GND
J 0
(-1250 3250);
DISPLAY 1.170213 (-1250 3250);
PAINT GREEN (-1250 3250);
DISPLAY INVISIBLE (-1250 3250);
FORCEPROP 1 LAST BODY_TYPE PLUMBING
J 0
(-1295 3057);
DISPLAY 0.340426 (-1295 3057);
PAINT GREEN (-1295 3057);
DISPLAY INVISIBLE (-1295 3057);
FORCEPROP 1 LAST VOLTAGE 0
J 0
(-1250 3100);
PAINT SKYBLUE (-1250 3100);
DISPLAY INVISIBLE (-1250 3100);
FORCEPROP 2 LAST CDS_LIB mstr_symbols
J 0
(-1250 3100);
PAINT ORANGE (-1250 3100);
DISPLAY INVISIBLE (-1250 3100);
FORCEPROP 1 LAST PATH I60
J 0
(-1175 3100);
DISPLAY 0.872340 (-1175 3100);
PAINT AQUA (-1175 3100);
DISPLAY INVISIBLE (-1175 3100);
FORCEPROP 2 LAST ROOM VDDQ_KLM_PWR_VR
J 0
(-1825 3175);
DISPLAY 1.361702 (-1825 3175);
PAINT ORANGE (-1825 3175);
DISPLAY INVISIBLE (-1825 3175);
FORCEPROP 1 LAST SIZE 1B
J 0
(-1175 3050);
DISPLAY 1.170213 (-1175 3050);
PAINT AQUA (-1175 3050);
DISPLAY INVISIBLE (-1175 3050);
FORCEADD GND..1
(-1475 3150);
FORCEPROP 3 LASTPIN (-1475 3200) SIG_NAME GND\g
J 0
(-1465 3210);
DISPLAY 0.659574 (-1465 3210);
PAINT MONO (-1465 3210);
DISPLAY INVISIBLE (-1465 3210);
FORCEPROP 1 LAST HDL_POWER GND
J 0
(-1475 3300);
DISPLAY 1.170213 (-1475 3300);
PAINT GREEN (-1475 3300);
DISPLAY INVISIBLE (-1475 3300);
FORCEPROP 1 LAST BODY_TYPE PLUMBING
J 0
(-1520 3107);
DISPLAY 0.340426 (-1520 3107);
PAINT GREEN (-1520 3107);
DISPLAY INVISIBLE (-1520 3107);
FORCEPROP 1 LAST PATH I61
J 0
(-1400 3150);
DISPLAY 0.872340 (-1400 3150);
PAINT AQUA (-1400 3150);
DISPLAY INVISIBLE (-1400 3150);
FORCEPROP 1 LAST SIZE 1B
J 0
(-1400 3100);
DISPLAY 1.170213 (-1400 3100);
PAINT AQUA (-1400 3100);
DISPLAY INVISIBLE (-1400 3100);
FORCEPROP 2 LAST CDS_LIB mstr_symbols
J 0
(-1475 3150);
PAINT ORANGE (-1475 3150);
DISPLAY INVISIBLE (-1475 3150);
FORCEPROP 1 LAST VOLTAGE 0
J 0
(-1475 3150);
PAINT SKYBLUE (-1475 3150);
DISPLAY INVISIBLE (-1475 3150);
FORCEPROP 2 LAST ROOM VDDQ_KLM_PWR_VR
J 0
(-2050 3225);
DISPLAY 1.361702 (-2050 3225);
PAINT ORANGE (-2050 3225);
DISPLAY INVISIBLE (-2050 3225);
FORCEADD OFFPAGE..2
R 2
(-2275 3550);
FORCEPROP 2 LAST $XR0 226 
J 0
(-2530 3550);
DISPLAY 0.638298 (-2530 3550);
PAINT MONO (-2530 3550);
FORCEPROP 1 LAST COMMENT_BODY TRUE
J 2
(-2230 3455);
DISPLAY 1.170213 (-2230 3455);
PAINT GREEN (-2230 3455);
DISPLAY INVISIBLE (-2230 3455);
FORCEPROP 1 LAST OFFPAGE TRUE
J 2
(-2600 3425);
DISPLAY 1.170213 (-2600 3425);
PAINT GREEN (-2600 3425);
DISPLAY INVISIBLE (-2600 3425);
FORCEPROP 2 LAST PATH I62
J 0
(-2550 3600);
DISPLAY 1.021277 (-2550 3600);
PAINT ORANGE (-2550 3600);
DISPLAY INVISIBLE (-2550 3600);
FORCEPROP 2 LAST CDS_LIB mstr_standard
J 2
(-2275 3550);
PAINT ORANGE (-2275 3550);
DISPLAY INVISIBLE (-2275 3550);
FORCEPROP 2 LAST ROOM VDDQ_KLM_PWR_VR
J 0
(-2825 3625);
DISPLAY 1.361702 (-2825 3625);
PAINT ORANGE (-2825 3625);
DISPLAY INVISIBLE (-2825 3625);
FORCEADD OFFPAGE..1
(-2275 3050);
FORCEPROP 2 LAST $XR2 223 
J 0
(-2736 3050);
DISPLAY 0.638298 (-2736 3050);
PAINT MONO (-2736 3050);
FORCEPROP 2 LAST $XR0 55 
J 0
(-2496 3050);
DISPLAY 0.638298 (-2496 3050);
PAINT MONO (-2496 3050);
FORCEPROP 2 LAST $XR1 193 
J 0
(-2616 3050);
DISPLAY 0.638298 (-2616 3050);
PAINT MONO (-2616 3050);
FORCEPROP 1 LAST COMMENT_BODY TRUE
J 0
(-2150 2950);
DISPLAY 1.170213 (-2150 2950);
PAINT GREEN (-2150 2950);
DISPLAY INVISIBLE (-2150 2950);
FORCEPROP 1 LAST OFFPAGE TRUE
J 0
(-1950 2925);
DISPLAY 1.170213 (-1950 2925);
PAINT GREEN (-1950 2925);
DISPLAY INVISIBLE (-1950 2925);
FORCEPROP 2 LAST PATH I63
J 0
(-2450 3100);
DISPLAY 1.021277 (-2450 3100);
PAINT ORANGE (-2450 3100);
DISPLAY INVISIBLE (-2450 3100);
FORCEPROP 2 LAST ROOM VDDQ_KLM_PWR_VR
J 0
(-2825 3125);
DISPLAY 1.361702 (-2825 3125);
PAINT ORANGE (-2825 3125);
DISPLAY INVISIBLE (-2825 3125);
FORCEPROP 2 LAST CDS_LIB mstr_standard
J 0
(-2275 3050);
PAINT ORANGE (-2275 3050);
DISPLAY INVISIBLE (-2275 3050);
FORCEADD OFFPAGE..1
(-2250 2325);
FORCEPROP 2 LAST $XR0 227 
J 0
(-2502 2325);
DISPLAY 0.638298 (-2502 2325);
PAINT MONO (-2502 2325);
FORCEPROP 1 LAST COMMENT_BODY TRUE
J 0
(-2125 2225);
DISPLAY 1.170213 (-2125 2225);
PAINT GREEN (-2125 2225);
DISPLAY INVISIBLE (-2125 2225);
FORCEPROP 1 LAST OFFPAGE TRUE
J 0
(-1925 2200);
DISPLAY 1.170213 (-1925 2200);
PAINT GREEN (-1925 2200);
DISPLAY INVISIBLE (-1925 2200);
FORCEPROP 2 LAST CDS_LIB mstr_standard
J 0
(-2250 2325);
PAINT ORANGE (-2250 2325);
DISPLAY INVISIBLE (-2250 2325);
FORCEPROP 2 LAST PATH I64
J 0
(-2200 2400);
DISPLAY 1.021277 (-2200 2400);
PAINT ORANGE (-2200 2400);
DISPLAY INVISIBLE (-2200 2400);
FORCEPROP 2 LAST ROOM VDDQ_KLM_PWR_VR
J 0
(-2800 2400);
DISPLAY 1.361702 (-2800 2400);
PAINT ORANGE (-2800 2400);
DISPLAY INVISIBLE (-2800 2400);
FORCEADD OFFPAGE..1
(-2250 2275);
FORCEPROP 2 LAST $XR0 227 
J 0
(-2502 2275);
DISPLAY 0.638298 (-2502 2275);
PAINT MONO (-2502 2275);
FORCEPROP 1 LAST COMMENT_BODY TRUE
J 0
(-2125 2175);
DISPLAY 1.170213 (-2125 2175);
PAINT GREEN (-2125 2175);
DISPLAY INVISIBLE (-2125 2175);
FORCEPROP 1 LAST OFFPAGE TRUE
J 0
(-1925 2150);
DISPLAY 1.170213 (-1925 2150);
PAINT GREEN (-1925 2150);
DISPLAY INVISIBLE (-1925 2150);
FORCEPROP 2 LAST PATH I65
J 0
(-2200 2350);
DISPLAY 1.021277 (-2200 2350);
PAINT ORANGE (-2200 2350);
DISPLAY INVISIBLE (-2200 2350);
FORCEPROP 2 LAST CDS_LIB mstr_standard
J 0
(-2250 2275);
PAINT ORANGE (-2250 2275);
DISPLAY INVISIBLE (-2250 2275);
FORCEPROP 2 LAST ROOM VDDQ_KLM_PWR_VR
J 0
(-2800 2350);
DISPLAY 1.361702 (-2800 2350);
PAINT ORANGE (-2800 2350);
DISPLAY INVISIBLE (-2800 2350);
FORCEADD OFFPAGE..1
(-2250 2125);
FORCEPROP 2 LAST $XR0 227 
J 0
(-2502 2125);
DISPLAY 0.638298 (-2502 2125);
PAINT MONO (-2502 2125);
FORCEPROP 1 LAST COMMENT_BODY TRUE
J 0
(-2125 2025);
DISPLAY 1.170213 (-2125 2025);
PAINT GREEN (-2125 2025);
DISPLAY INVISIBLE (-2125 2025);
FORCEPROP 1 LAST OFFPAGE TRUE
J 0
(-1925 2000);
DISPLAY 1.170213 (-1925 2000);
PAINT GREEN (-1925 2000);
DISPLAY INVISIBLE (-1925 2000);
FORCEPROP 2 LAST PATH I67
J 0
(-2200 2200);
DISPLAY 1.021277 (-2200 2200);
PAINT ORANGE (-2200 2200);
DISPLAY INVISIBLE (-2200 2200);
FORCEPROP 2 LAST CDS_LIB mstr_standard
J 0
(-2250 2125);
PAINT ORANGE (-2250 2125);
DISPLAY INVISIBLE (-2250 2125);
FORCEPROP 2 LAST ROOM VDDQ_KLM_PWR_VR
J 0
(-2800 2200);
DISPLAY 1.361702 (-2800 2200);
PAINT ORANGE (-2800 2200);
DISPLAY INVISIBLE (-2800 2200);
FORCEADD OFFPAGE..1
(-2250 2075);
FORCEPROP 2 LAST $XR0 227 
J 0
(-2502 2075);
DISPLAY 0.638298 (-2502 2075);
PAINT MONO (-2502 2075);
FORCEPROP 1 LAST COMMENT_BODY TRUE
J 0
(-2125 1975);
DISPLAY 1.170213 (-2125 1975);
PAINT GREEN (-2125 1975);
DISPLAY INVISIBLE (-2125 1975);
FORCEPROP 1 LAST OFFPAGE TRUE
J 0
(-1925 1950);
DISPLAY 1.170213 (-1925 1950);
PAINT GREEN (-1925 1950);
DISPLAY INVISIBLE (-1925 1950);
FORCEPROP 2 LAST PATH I68
J 0
(-2200 2150);
DISPLAY 1.021277 (-2200 2150);
PAINT ORANGE (-2200 2150);
DISPLAY INVISIBLE (-2200 2150);
FORCEPROP 2 LAST CDS_LIB mstr_standard
J 0
(-2250 2075);
PAINT ORANGE (-2250 2075);
DISPLAY INVISIBLE (-2250 2075);
FORCEPROP 2 LAST ROOM VDDQ_KLM_PWR_VR
J 0
(-2800 2150);
DISPLAY 1.361702 (-2800 2150);
PAINT ORANGE (-2800 2150);
DISPLAY INVISIBLE (-2800 2150);
FORCEADD PVCCIO_CPU1..1
(3800 3000);
FORCEPROP 3 LASTPIN (3800 2950) SIG_NAME PVCCIO_CPU1\g
J 0
(3810 2960);
DISPLAY 0.659574 (3810 2960);
PAINT MONO (3810 2960);
DISPLAY INVISIBLE (3810 2960);
FORCEPROP 1 LAST HDL_POWER PVCCIO_CPU1
J 1
(3800 3050);
DISPLAY 0.872340 (3800 3050);
PAINT GREEN (3800 3050);
DISPLAY INVISIBLE (3800 3050);
FORCEPROP 1 LAST BODY_TYPE PLUMBING
J 0
(3755 2957);
DISPLAY 0.340426 (3755 2957);
PAINT GREEN (3755 2957);
DISPLAY INVISIBLE (3755 2957);
FORCEPROP 1 LAST PATH I7
J 0
(3850 3025);
DISPLAY 0.872340 (3850 3025);
PAINT AQUA (3850 3025);
DISPLAY INVISIBLE (3850 3025);
FORCEPROP 1 LAST VOLTAGE 1.1V
J 0
(3755 2957);
DISPLAY 0.340426 (3755 2957);
PAINT SKYBLUE (3755 2957);
DISPLAY INVISIBLE (3755 2957);
FORCEPROP 2 LAST CDS_LIB mstr_symbols
J 0
(3800 3000);
PAINT ORANGE (3800 3000);
DISPLAY INVISIBLE (3800 3000);
FORCEADD OFFPAGE..1
(-2250 1875);
FORCEPROP 2 LAST $XR0 197 
J 0
(-2502 1875);
DISPLAY 0.638298 (-2502 1875);
PAINT MONO (-2502 1875);
FORCEPROP 1 LAST COMMENT_BODY TRUE
J 0
(-2125 1775);
DISPLAY 1.170213 (-2125 1775);
PAINT GREEN (-2125 1775);
DISPLAY INVISIBLE (-2125 1775);
FORCEPROP 1 LAST OFFPAGE TRUE
J 0
(-1925 1750);
DISPLAY 1.170213 (-1925 1750);
PAINT GREEN (-1925 1750);
DISPLAY INVISIBLE (-1925 1750);
FORCEPROP 2 LAST PATH I70
J 0
(-2200 1950);
DISPLAY 1.021277 (-2200 1950);
PAINT ORANGE (-2200 1950);
DISPLAY INVISIBLE (-2200 1950);
FORCEPROP 2 LAST CDS_LIB mstr_standard
J 0
(-2250 1875);
PAINT ORANGE (-2250 1875);
DISPLAY INVISIBLE (-2250 1875);
FORCEPROP 2 LAST ROOM VDDQ_KLM_PWR_VR
J 0
(-2800 1950);
DISPLAY 1.361702 (-2800 1950);
PAINT ORANGE (-2800 1950);
DISPLAY INVISIBLE (-2800 1950);
FORCEADD OFFPAGE..1
(-2250 1775);
FORCEPROP 2 LAST $XR0 227 
J 0
(-2502 1775);
DISPLAY 0.638298 (-2502 1775);
PAINT MONO (-2502 1775);
FORCEPROP 1 LAST COMMENT_BODY TRUE
J 0
(-2125 1675);
DISPLAY 1.170213 (-2125 1675);
PAINT GREEN (-2125 1675);
DISPLAY INVISIBLE (-2125 1675);
FORCEPROP 1 LAST OFFPAGE TRUE
J 0
(-1925 1650);
DISPLAY 1.170213 (-1925 1650);
PAINT GREEN (-1925 1650);
DISPLAY INVISIBLE (-1925 1650);
FORCEPROP 2 LAST PATH I71
J 0
(-2200 1850);
DISPLAY 1.021277 (-2200 1850);
PAINT ORANGE (-2200 1850);
DISPLAY INVISIBLE (-2200 1850);
FORCEPROP 2 LAST CDS_LIB mstr_standard
J 0
(-2250 1775);
PAINT ORANGE (-2250 1775);
DISPLAY INVISIBLE (-2250 1775);
FORCEPROP 2 LAST ROOM VDDQ_KLM_PWR_VR
J 0
(-2800 1850);
DISPLAY 1.361702 (-2800 1850);
PAINT ORANGE (-2800 1850);
DISPLAY INVISIBLE (-2800 1850);
FORCEADD OFFPAGE..1
(-2250 1925);
FORCEPROP 2 LAST $XR0 226 
J 0
(-2502 1925);
DISPLAY 0.638298 (-2502 1925);
PAINT MONO (-2502 1925);
FORCEPROP 1 LAST COMMENT_BODY TRUE
J 0
(-2125 1825);
DISPLAY 1.170213 (-2125 1825);
PAINT GREEN (-2125 1825);
DISPLAY INVISIBLE (-2125 1825);
FORCEPROP 1 LAST OFFPAGE TRUE
J 0
(-1925 1800);
DISPLAY 1.170213 (-1925 1800);
PAINT GREEN (-1925 1800);
DISPLAY INVISIBLE (-1925 1800);
FORCEPROP 2 LAST ROOM VDDQ_KLM_PWR_VR
J 0
(-2800 2000);
DISPLAY 1.361702 (-2800 2000);
PAINT ORANGE (-2800 2000);
DISPLAY INVISIBLE (-2800 2000);
FORCEPROP 2 LAST CDS_LIB mstr_standard
J 0
(-2250 1925);
PAINT ORANGE (-2250 1925);
DISPLAY INVISIBLE (-2250 1925);
FORCEPROP 2 LAST PATH I72
J 0
(-2200 2000);
DISPLAY 1.021277 (-2200 2000);
PAINT ORANGE (-2200 2000);
DISPLAY INVISIBLE (-2200 2000);
FORCEADD OFFPAGE..1
(-2250 1475);
FORCEPROP 2 LAST $XR0 191 
J 0
(-2502 1475);
DISPLAY 0.638298 (-2502 1475);
PAINT MONO (-2502 1475);
FORCEPROP 1 LAST COMMENT_BODY TRUE
J 0
(-2125 1375);
DISPLAY 1.170213 (-2125 1375);
PAINT GREEN (-2125 1375);
DISPLAY INVISIBLE (-2125 1375);
FORCEPROP 1 LAST OFFPAGE TRUE
J 0
(-1925 1350);
DISPLAY 1.170213 (-1925 1350);
PAINT GREEN (-1925 1350);
DISPLAY INVISIBLE (-1925 1350);
FORCEPROP 2 LAST PATH I74
J 0
(-2200 1550);
DISPLAY 1.021277 (-2200 1550);
PAINT ORANGE (-2200 1550);
DISPLAY INVISIBLE (-2200 1550);
FORCEPROP 2 LAST CDS_LIB mstr_standard
J 0
(-2250 1475);
PAINT ORANGE (-2250 1475);
DISPLAY INVISIBLE (-2250 1475);
FORCEPROP 2 LAST ROOM VDDQ_KLM_PWR_VR
J 0
(-2800 1550);
DISPLAY 1.361702 (-2800 1550);
PAINT ORANGE (-2800 1550);
DISPLAY INVISIBLE (-2800 1550);
FORCEADD RES..2
(575 275);
FORCEPROP 1 LAST PART_NUMBER G21796-297
J 0
(615 150);
DISPLAY 0.617021 (615 150);
PAINT BLUE (615 150);
FORCEPROP 1 LAST LOCATION R1B15
J 0
(620 400);
DISPLAY 0.617021 (620 400);
PAINT AQUA (620 400);
FORCEPROP 1 LAST VALUE 5.36K
J 0
(620 350);
DISPLAY 0.617021 (620 350);
PAINT SKYBLUE (620 350);
FORCEPROP 1 LAST TOLERANCE 1.0%
J 0
(620 300);
DISPLAY 0.617021 (620 300);
PAINT SKYBLUE (620 300);
FORCEPROP 1 LAST WATTAGE 1/16W
J 0
(615 250);
DISPLAY 0.617021 (615 250);
PAINT SKYBLUE (615 250);
FORCEPROP 1 LAST MATERIAL CHIP
J 0
(615 200);
DISPLAY 0.617021 (615 200);
PAINT SKYBLUE (615 200);
FORCEPROP 1 LAST PACK_TYPE 0402
J 0
(615 100);
DISPLAY 0.617021 (615 100);
PAINT SKYBLUE (615 100);
FORCEPROP 2 LAST CDS_SEC 1
J 0
(625 500);
PAINT MONO (625 500);
DISPLAY INVISIBLE (625 500);
FORCEPROP 2 LAST $SEC 1
J 0
(625 500);
PAINT MONO (625 500);
DISPLAY INVISIBLE (625 500);
FORCEPROP 0 LAST ROOM VDDQ_KLM_PWR_VR
J 0
(625 500);
DISPLAY 1.021277 (625 500);
PAINT ORANGE (625 500);
DISPLAY INVISIBLE (625 500);
FORCEPROP 2 LAST CDS_LIB mstr_discrete
J 0
(575 275);
PAINT ORANGE (575 275);
DISPLAY INVISIBLE (575 275);
FORCEPROP 2 LAST CDS_LOCATION R1B15
J 0
(620 400);
DISPLAY 0.617021 (620 400);
PAINT AQUA (620 400);
DISPLAY INVISIBLE (620 400);
FORCEPROP 1 LAST PATH I77
J 0
(625 450);
DISPLAY 0.978723 (625 450);
PAINT WHITE (625 450);
DISPLAY INVISIBLE (625 450);
FORCEPROP 1 LASTPIN (575 375) $PN 1
J 0
(580 337);
DISPLAY 0.787234 (580 337);
PAINT ORANGE (580 337);
DISPLAY INVISIBLE (580 337);
FORCEPROP 1 LASTPIN (575 175) $PN 2
J 0
(580 185);
DISPLAY 0.787234 (580 185);
PAINT ORANGE (580 185);
DISPLAY INVISIBLE (580 185);
FORCEADD RES..2
(200 275);
FORCEPROP 1 LAST PART_NUMBER G21796-043
J 0
(240 150);
DISPLAY 0.617021 (240 150);
PAINT BLUE (240 150);
FORCEPROP 1 LAST LOCATION R1B12
J 0
(245 400);
DISPLAY 0.617021 (245 400);
PAINT AQUA (245 400);
FORCEPROP 1 LAST VALUE 3.16K
J 0
(245 350);
DISPLAY 0.617021 (245 350);
PAINT SKYBLUE (245 350);
FORCEPROP 1 LAST TOLERANCE 1%
J 0
(245 300);
DISPLAY 0.617021 (245 300);
PAINT SKYBLUE (245 300);
FORCEPROP 1 LAST PACK_TYPE 0402
J 0
(240 100);
DISPLAY 0.617021 (240 100);
PAINT SKYBLUE (240 100);
FORCEPROP 1 LAST MATERIAL CHIP
J 0
(240 200);
DISPLAY 0.617021 (240 200);
PAINT SKYBLUE (240 200);
FORCEPROP 1 LAST WATTAGE 1/16W
J 0
(240 250);
DISPLAY 0.617021 (240 250);
PAINT SKYBLUE (240 250);
FORCEPROP 2 LAST CDS_SEC 1
J 0
(250 500);
PAINT MONO (250 500);
DISPLAY INVISIBLE (250 500);
FORCEPROP 2 LAST $SEC 1
J 0
(250 500);
PAINT MONO (250 500);
DISPLAY INVISIBLE (250 500);
FORCEPROP 0 LAST ROOM VDDQ_KLM_PWR_VR
J 0
(250 500);
DISPLAY 1.021277 (250 500);
PAINT ORANGE (250 500);
DISPLAY INVISIBLE (250 500);
FORCEPROP 2 LAST CDS_LIB mstr_discrete
J 0
(200 275);
PAINT ORANGE (200 275);
DISPLAY INVISIBLE (200 275);
FORCEPROP 2 LAST CDS_LOCATION R1B12
J 0
(245 400);
DISPLAY 0.617021 (245 400);
PAINT AQUA (245 400);
DISPLAY INVISIBLE (245 400);
FORCEPROP 1 LAST PATH I78
J 0
(250 450);
DISPLAY 0.978723 (250 450);
PAINT WHITE (250 450);
DISPLAY INVISIBLE (250 450);
FORCEPROP 1 LASTPIN (200 375) $PN 1
J 0
(205 337);
DISPLAY 0.787234 (205 337);
PAINT ORANGE (205 337);
DISPLAY INVISIBLE (205 337);
FORCEPROP 1 LASTPIN (200 175) $PN 2
J 0
(205 185);
DISPLAY 0.787234 (205 185);
PAINT ORANGE (205 185);
DISPLAY INVISIBLE (205 185);
FORCEADD RES..2
(2075 3025);
FORCEPROP 1 LASTPIN (2075 3125) $PN 1
J 0
(2080 3087);
DISPLAY 0.617021 (2080 3087);
PAINT ORANGE (2080 3087);
FORCEPROP 1 LAST VALUE 1.00K
J 0
(2120 3100);
DISPLAY 0.617021 (2120 3100);
PAINT SKYBLUE (2120 3100);
FORCEPROP 1 LAST LOCATION R1B1
J 0
(2120 3150);
DISPLAY 0.617021 (2120 3150);
PAINT AQUA (2120 3150);
FORCEPROP 1 LAST TOLERANCE 1%
J 0
(2120 3050);
DISPLAY 0.617021 (2120 3050);
PAINT SKYBLUE (2120 3050);
FORCEPROP 1 LAST PART_NUMBER G21796-026
J 0
(2115 2900);
DISPLAY 0.617021 (2115 2900);
PAINT BLUE (2115 2900);
FORCEPROP 1 LAST PACK_TYPE 0402
J 0
(2115 2850);
DISPLAY 0.617021 (2115 2850);
PAINT SKYBLUE (2115 2850);
FORCEPROP 1 LAST MATERIAL CHIP
J 0
(2115 2950);
DISPLAY 0.617021 (2115 2950);
PAINT SKYBLUE (2115 2950);
FORCEPROP 1 LAST WATTAGE 1/16W
J 0
(2115 3000);
DISPLAY 0.617021 (2115 3000);
PAINT SKYBLUE (2115 3000);
FORCEPROP 1 LASTPIN (2075 2925) $PN 2
J 0
(2080 2935);
DISPLAY 0.617021 (2080 2935);
PAINT ORANGE (2080 2935);
FORCEPROP 2 LAST SEC_TYPE 0402
J 0
(2125 3250);
DISPLAY 1.021277 (2125 3250);
PAINT ORANGE (2125 3250);
DISPLAY INVISIBLE (2125 3250);
FORCEPROP 2 LAST SEC 1
J 0
(2125 3250);
DISPLAY 0.680851 (2125 3250);
PAINT MONO (2125 3250);
DISPLAY INVISIBLE (2125 3250);
FORCEPROP 2 LAST CDS_LOCATION R1B1
J 0
(2120 3150);
DISPLAY 0.617021 (2120 3150);
PAINT AQUA (2120 3150);
DISPLAY INVISIBLE (2120 3150);
FORCEPROP 1 LAST PATH I79
J 0
(2125 3200);
DISPLAY 0.978723 (2125 3200);
PAINT WHITE (2125 3200);
DISPLAY INVISIBLE (2125 3200);
FORCEPROP 0 LAST ROOM RQ_PVDDQ_KLM_VRHOT_LVT3_N
J 0
(2125 3250);
DISPLAY 1.021277 (2125 3250);
PAINT ORANGE (2125 3250);
DISPLAY INVISIBLE (2125 3250);
FORCEPROP 2 LAST CDS_LIB mstr_discrete
J 0
(2075 3025);
PAINT ORANGE (2075 3025);
DISPLAY INVISIBLE (2075 3025);
FORCEADD RES..2
(3800 2775);
FORCEPROP 1 LAST PART_NUMBER G21796-017
J 0
(3840 2650);
DISPLAY 0.617021 (3840 2650);
PAINT BLUE (3840 2650);
FORCEPROP 1 LAST LOCATION R9M7
J 0
(3845 2900);
DISPLAY 0.617021 (3845 2900);
PAINT AQUA (3845 2900);
FORCEPROP 1 LAST VALUE 100.0
J 0
(3845 2850);
DISPLAY 0.617021 (3845 2850);
PAINT SKYBLUE (3845 2850);
FORCEPROP 1 LAST TOLERANCE 1%
J 0
(3845 2800);
DISPLAY 0.617021 (3845 2800);
PAINT SKYBLUE (3845 2800);
FORCEPROP 1 LAST MATERIAL EMPTY
J 0
(3840 2700);
DISPLAY 0.617021 (3840 2700);
PAINT RED (3840 2700);
FORCEPROP 1 LAST PACK_TYPE 0402
J 0
(3840 2600);
DISPLAY 0.617021 (3840 2600);
PAINT SKYBLUE (3840 2600);
FORCEPROP 1 LAST WATTAGE 1/16W
J 0
(3840 2750);
DISPLAY 0.617021 (3840 2750);
PAINT SKYBLUE (3840 2750);
FORCEPROP 1 LASTPIN (3800 2875) $PN 1
J 0
(3805 2837);
DISPLAY 0.617021 (3805 2837);
PAINT ORANGE (3805 2837);
FORCEPROP 1 LASTPIN (3800 2675) $PN 2
J 0
(3805 2685);
DISPLAY 0.617021 (3805 2685);
PAINT ORANGE (3805 2685);
FORCEPROP 2 LAST SEC_TYPE 0402
J 0
(3850 3025);
DISPLAY 1.021277 (3850 3025);
PAINT ORANGE (3850 3025);
DISPLAY INVISIBLE (3850 3025);
FORCEPROP 2 LAST SEC 1
J 0
(3850 3025);
DISPLAY 0.680851 (3850 3025);
PAINT MONO (3850 3025);
DISPLAY INVISIBLE (3850 3025);
FORCEPROP 2 LAST CDS_LOCATION R9M7
J 0
(3845 2900);
DISPLAY 0.617021 (3845 2900);
PAINT AQUA (3845 2900);
DISPLAY INVISIBLE (3845 2900);
FORCEPROP 1 LAST PATH I8
J 0
(3850 2950);
DISPLAY 0.978723 (3850 2950);
PAINT WHITE (3850 2950);
DISPLAY INVISIBLE (3850 2950);
FORCEPROP 2 LAST ROOM VDDQ_KLM_PWR_VR
J 0
(3850 2950);
DISPLAY 1.361702 (3850 2950);
PAINT ORANGE (3850 2950);
DISPLAY INVISIBLE (3850 2950);
FORCEPROP 2 LAST CDS_LIB mstr_discrete
J 0
(3800 2775);
PAINT ORANGE (3800 2775);
DISPLAY INVISIBLE (3800 2775);
FORCEADD CAP..1
(2900 975);
FORCEPROP 1 LAST PART_NUMBER A36096-046
J 0
(2950 825);
DISPLAY 0.617021 (2950 825);
PAINT BLUE (2950 825);
FORCEPROP 1 LAST VALUE 1000PF
J 0
(2950 1025);
DISPLAY 0.617021 (2950 1025);
PAINT SKYBLUE (2950 1025);
FORCEPROP 1 LAST PACK_TYPE 0402LF
J 0
(2950 775);
DISPLAY 0.617021 (2950 775);
PAINT SKYBLUE (2950 775);
FORCEPROP 1 LAST LOCATION C1B4
J 0
(2950 1075);
DISPLAY 0.617021 (2950 1075);
PAINT AQUA (2950 1075);
FORCEPROP 1 LASTPIN (2900 1075) $PN 1
J 0
(2910 1055);
DISPLAY 0.617021 (2910 1055);
PAINT ORANGE (2910 1055);
FORCEPROP 1 LAST TOLERANCE 10%
J 0
(2950 925);
DISPLAY 0.617021 (2950 925);
PAINT SKYBLUE (2950 925);
FORCEPROP 1 LAST VOLTAGE 50V
J 0
(2950 975);
DISPLAY 0.617021 (2950 975);
PAINT SKYBLUE (2950 975);
FORCEPROP 1 LAST MATERIAL X7R
J 0
(2950 875);
DISPLAY 0.617021 (2950 875);
PAINT SKYBLUE (2950 875);
FORCEPROP 1 LASTPIN (2900 875) $PN 2
J 0
(2910 855);
DISPLAY 0.617021 (2910 855);
PAINT ORANGE (2910 855);
FORCEPROP 2 LAST SEC_TYPE 0402LF
J 0
(2950 1175);
DISPLAY 1.021277 (2950 1175);
PAINT ORANGE (2950 1175);
DISPLAY INVISIBLE (2950 1175);
FORCEPROP 2 LAST SEC 1
J 0
(2950 1175);
DISPLAY 0.680851 (2950 1175);
PAINT MONO (2950 1175);
DISPLAY INVISIBLE (2950 1175);
FORCEPROP 2 LAST CDS_LOCATION C1B4
J 0
(2950 1075);
DISPLAY 0.617021 (2950 1075);
PAINT AQUA (2950 1075);
DISPLAY INVISIBLE (2950 1075);
FORCEPROP 1 LAST PATH I80
J 0
(2950 1125);
DISPLAY 0.978723 (2950 1125);
PAINT WHITE (2950 1125);
DISPLAY INVISIBLE (2950 1125);
FORCEPROP 0 LAST ROOM VDDQ_KLM_PWR_VR
J 0
(2950 1175);
DISPLAY 1.021277 (2950 1175);
PAINT ORANGE (2950 1175);
DISPLAY INVISIBLE (2950 1175);
FORCEPROP 2 LAST CDS_LIB mstr_discrete
J 0
(2900 975);
PAINT MONO (2900 975);
DISPLAY INVISIBLE (2900 975);
FORCEADD GND..1
(2900 700);
FORCEPROP 3 LASTPIN (2900 750) SIG_NAME GND\g
J 0
(2910 760);
DISPLAY 0.659574 (2910 760);
PAINT MONO (2910 760);
DISPLAY INVISIBLE (2910 760);
FORCEPROP 1 LAST HDL_POWER GND
J 0
(2900 850);
DISPLAY 1.170213 (2900 850);
PAINT GREEN (2900 850);
DISPLAY INVISIBLE (2900 850);
FORCEPROP 1 LAST BODY_TYPE PLUMBING
J 0
(2855 657);
DISPLAY 0.340426 (2855 657);
PAINT GREEN (2855 657);
DISPLAY INVISIBLE (2855 657);
FORCEPROP 1 LAST PATH I81
J 0
(2975 700);
DISPLAY 0.872340 (2975 700);
PAINT AQUA (2975 700);
DISPLAY INVISIBLE (2975 700);
FORCEPROP 1 LAST SIZE 1B
J 0
(2975 650);
DISPLAY 1.170213 (2975 650);
PAINT AQUA (2975 650);
DISPLAY INVISIBLE (2975 650);
FORCEPROP 2 LAST CDS_LIB mstr_symbols
J 0
(2900 700);
PAINT MONO (2900 700);
DISPLAY INVISIBLE (2900 700);
FORCEPROP 1 LAST VOLTAGE 0
J 0
(2900 700);
PAINT SKYBLUE (2900 700);
DISPLAY INVISIBLE (2900 700);
FORCEPROP 2 LAST ROOM VDDQ_KLM_PWR_VR
J 0
(2325 775);
DISPLAY 1.361702 (2325 775);
PAINT ORANGE (2325 775);
DISPLAY INVISIBLE (2325 775);
FORCEADD RES..1
(3275 2425);
FORCEPROP 1 LAST WATTAGE 1/16W
J 2
(3250 2275);
DISPLAY 0.617021 (3250 2275);
PAINT SKYBLUE (3250 2275);
FORCEPROP 1 LASTPIN (3175 2425) $PN 1
J 0
(3187 2437);
DISPLAY 0.617021 (3187 2437);
PAINT ORANGE (3187 2437);
FORCEPROP 1 LAST VALUE 33.2
J 2
(3250 2325);
DISPLAY 0.617021 (3250 2325);
PAINT SKYBLUE (3250 2325);
FORCEPROP 1 LAST MATERIAL CHIP
J 0
(3275 2275);
DISPLAY 0.617021 (3275 2275);
PAINT SKYBLUE (3275 2275);
FORCEPROP 1 LAST TOLERANCE 1%
J 0
(3275 2325);
DISPLAY 0.617021 (3275 2325);
PAINT SKYBLUE (3275 2325);
FORCEPROP 1 LAST PART_NUMBER G21796-074
J 0
(3150 2225);
DISPLAY 0.617021 (3150 2225);
PAINT BLUE (3150 2225);
FORCEPROP 1 LAST LOCATION R1B4
J 0
(3225 2475);
DISPLAY 0.617021 (3225 2475);
PAINT AQUA (3225 2475);
FORCEPROP 1 LASTPIN (3375 2425) $PN 2
J 0
(3337 2437);
DISPLAY 0.617021 (3337 2437);
PAINT ORANGE (3337 2437);
FORCEPROP 1 LAST PACK_TYPE 0402
J 0
(3375 2275);
DISPLAY 0.617021 (3375 2275);
PAINT SKYBLUE (3375 2275);
FORCEPROP 2 LAST CDS_LOCATION R1B4
J 0
(3225 2475);
DISPLAY 0.617021 (3225 2475);
PAINT AQUA (3225 2475);
DISPLAY INVISIBLE (3225 2475);
FORCEPROP 2 LAST CDS_LIB mstr_discrete
J 0
(3275 2425);
PAINT MONO (3275 2425);
DISPLAY INVISIBLE (3275 2425);
FORCEPROP 1 LAST PATH I82
J 0
(3225 2575);
DISPLAY 0.978723 (3225 2575);
PAINT WHITE (3225 2575);
DISPLAY INVISIBLE (3225 2575);
FORCEPROP 2 LAST SEC 1
J 0
(3225 2625);
DISPLAY 0.680851 (3225 2625);
PAINT MONO (3225 2625);
DISPLAY INVISIBLE (3225 2625);
FORCEPROP 2 LAST SEC_TYPE 0402
J 0
(3225 2625);
DISPLAY 1.021277 (3225 2625);
PAINT ORANGE (3225 2625);
DISPLAY INVISIBLE (3225 2625);
FORCEADD RES..1
(-1550 1475);
FORCEPROP 1 LAST VALUE 0.0
J 2
(-1650 1375);
DISPLAY 0.617021 (-1650 1375);
PAINT SKYBLUE (-1650 1375);
FORCEPROP 1 LAST WATTAGE 1/16W
J 2
(-1575 1325);
DISPLAY 0.617021 (-1575 1325);
PAINT SKYBLUE (-1575 1325);
FORCEPROP 1 LAST TOLERANCE 5%
J 0
(-1600 1375);
DISPLAY 0.617021 (-1600 1375);
PAINT SKYBLUE (-1600 1375);
FORCEPROP 1 LAST MATERIAL CHIP
J 0
(-1550 1325);
DISPLAY 0.617021 (-1550 1325);
PAINT SKYBLUE (-1550 1325);
FORCEPROP 1 LAST PART_NUMBER G21497-005
J 0
(-1700 1425);
DISPLAY 0.617021 (-1700 1425);
PAINT BLUE (-1700 1425);
FORCEPROP 1 LAST LOCATION R9M9
J 0
(-1600 1525);
DISPLAY 0.617021 (-1600 1525);
PAINT AQUA (-1600 1525);
FORCEPROP 1 LAST PACK_TYPE 0402
J 0
(-1475 1375);
DISPLAY 0.617021 (-1475 1375);
PAINT SKYBLUE (-1475 1375);
FORCEPROP 2 LAST CDS_LIB mstr_discrete
J 0
(-1550 1475);
PAINT ORANGE (-1550 1475);
DISPLAY INVISIBLE (-1550 1475);
FORCEPROP 1 LASTPIN (-1650 1475) $PN 1
J 0
(-1638 1487);
DISPLAY 0.787234 (-1638 1487);
PAINT ORANGE (-1638 1487);
DISPLAY INVISIBLE (-1638 1487);
FORCEPROP 2 LAST CDS_LOCATION R9M9
J 0
(-1600 1525);
DISPLAY 0.617021 (-1600 1525);
PAINT AQUA (-1600 1525);
DISPLAY INVISIBLE (-1600 1525);
FORCEPROP 2 LAST ROOM PVCCIN_CPU0_VR
J 0
(-1600 1575);
DISPLAY 1.361702 (-1600 1575);
PAINT ORANGE (-1600 1575);
DISPLAY INVISIBLE (-1600 1575);
FORCEPROP 1 LAST PATH I84
J 0
(-1600 1625);
DISPLAY 0.978723 (-1600 1625);
PAINT WHITE (-1600 1625);
DISPLAY INVISIBLE (-1600 1625);
FORCEPROP 2 LAST $SEC 1
J 0
(-1600 1675);
PAINT MONO (-1600 1675);
DISPLAY INVISIBLE (-1600 1675);
FORCEPROP 2 LAST CDS_SEC 1
J 0
(-1600 1675);
PAINT MONO (-1600 1675);
DISPLAY INVISIBLE (-1600 1675);
FORCEPROP 1 LASTPIN (-1450 1475) $PN 2
J 0
(-1488 1487);
DISPLAY 0.787234 (-1488 1487);
PAINT ORANGE (-1488 1487);
DISPLAY INVISIBLE (-1488 1487);
FORCEADD RES..2
(75 3550);
FORCEPROP 1 LAST VALUE 100.0K
J 0
(120 3625);
DISPLAY 0.617021 (120 3625);
PAINT SKYBLUE (120 3625);
FORCEPROP 1 LAST LOCATION R9M5
J 0
(120 3675);
DISPLAY 0.617021 (120 3675);
PAINT AQUA (120 3675);
FORCEPROP 1 LASTPIN (75 3650) $PN 1
J 0
(80 3612);
DISPLAY 0.617021 (80 3612);
PAINT ORANGE (80 3612);
FORCEPROP 1 LAST TOLERANCE 1%
J 0
(120 3575);
DISPLAY 0.617021 (120 3575);
PAINT SKYBLUE (120 3575);
FORCEPROP 1 LAST MATERIAL EMPTY
J 0
(115 3475);
DISPLAY 0.617021 (115 3475);
PAINT RED (115 3475);
FORCEPROP 1 LAST PART_NUMBER G21796-010
J 0
(115 3425);
DISPLAY 0.617021 (115 3425);
PAINT BLUE (115 3425);
FORCEPROP 1 LAST WATTAGE 1/16W
J 0
(115 3525);
DISPLAY 0.617021 (115 3525);
PAINT SKYBLUE (115 3525);
FORCEPROP 1 LAST PACK_TYPE 0402
J 0
(115 3375);
DISPLAY 0.617021 (115 3375);
PAINT SKYBLUE (115 3375);
FORCEPROP 1 LASTPIN (75 3450) $PN 2
J 0
(80 3460);
DISPLAY 0.617021 (80 3460);
PAINT ORANGE (80 3460);
FORCEPROP 0 LAST BOM_COST SM_CONTROLLER
J 0
(125 3875);
DISPLAY 1.021277 (125 3875);
PAINT ORANGE (125 3875);
DISPLAY INVISIBLE (125 3875);
FORCEPROP 2 LAST SEC_TYPE 0402
J 0
(125 3775);
DISPLAY 1.021277 (125 3775);
PAINT ORANGE (125 3775);
DISPLAY INVISIBLE (125 3775);
FORCEPROP 2 LAST SEC 1
J 0
(125 3775);
PAINT MONO (125 3775);
DISPLAY INVISIBLE (125 3775);
FORCEPROP 1 LAST PATH I85
J 0
(125 3725);
DISPLAY 0.978723 (125 3725);
PAINT WHITE (125 3725);
DISPLAY INVISIBLE (125 3725);
FORCEPROP 0 LAST ROOM BMC
J 0
(125 3775);
DISPLAY 0.617021 (125 3775);
PAINT ORANGE (125 3775);
DISPLAY INVISIBLE (125 3775);
FORCEPROP 2 LAST CDS_LOCATION R9M5
J 0
(120 3675);
DISPLAY 0.617021 (120 3675);
PAINT AQUA (120 3675);
DISPLAY INVISIBLE (120 3675);
FORCEPROP 2 LAST CDS_LIB mstr_discrete
J 0
(75 3550);
PAINT ORANGE (75 3550);
DISPLAY INVISIBLE (75 3550);
FORCEADD RES..1
(-1625 2725);
FORCEPROP 1 LAST WATTAGE 1/16W
J 2
(-1650 2575);
DISPLAY 0.617021 (-1650 2575);
PAINT SKYBLUE (-1650 2575);
FORCEPROP 1 LAST VALUE 0.0
J 2
(-1725 2625);
DISPLAY 0.617021 (-1725 2625);
PAINT SKYBLUE (-1725 2625);
FORCEPROP 1 LAST TOLERANCE 5%
J 0
(-1675 2625);
DISPLAY 0.617021 (-1675 2625);
PAINT SKYBLUE (-1675 2625);
FORCEPROP 1 LAST MATERIAL CHIP
J 0
(-1625 2575);
DISPLAY 0.617021 (-1625 2575);
PAINT SKYBLUE (-1625 2575);
FORCEPROP 1 LAST PACK_TYPE 0402
J 0
(-1550 2625);
DISPLAY 0.617021 (-1550 2625);
PAINT SKYBLUE (-1550 2625);
FORCEPROP 1 LAST PART_NUMBER G21497-005
J 0
(-1775 2675);
DISPLAY 0.617021 (-1775 2675);
PAINT BLUE (-1775 2675);
FORCEPROP 1 LAST LOCATION R9M11
J 0
(-1675 2775);
DISPLAY 0.617021 (-1675 2775);
PAINT AQUA (-1675 2775);
FORCEPROP 2 LAST CDS_LOCATION R9M11
J 0
(-1675 2775);
DISPLAY 0.617021 (-1675 2775);
PAINT AQUA (-1675 2775);
DISPLAY INVISIBLE (-1675 2775);
FORCEPROP 1 LASTPIN (-1725 2725) $PN 1
J 0
(-1713 2737);
DISPLAY 0.787234 (-1713 2737);
PAINT ORANGE (-1713 2737);
DISPLAY INVISIBLE (-1713 2737);
FORCEPROP 1 LASTPIN (-1525 2725) $PN 2
J 0
(-1563 2737);
DISPLAY 0.787234 (-1563 2737);
PAINT ORANGE (-1563 2737);
DISPLAY INVISIBLE (-1563 2737);
FORCEPROP 2 LAST CDS_LIB mstr_discrete
J 0
(-1625 2725);
PAINT ORANGE (-1625 2725);
DISPLAY INVISIBLE (-1625 2725);
FORCEPROP 1 LAST PATH I87
J 0
(-1675 2875);
DISPLAY 0.978723 (-1675 2875);
PAINT WHITE (-1675 2875);
DISPLAY INVISIBLE (-1675 2875);
FORCEPROP 2 LAST ROOM PVCCIN_CPU0_VR
J 0
(-1675 2825);
DISPLAY 1.361702 (-1675 2825);
PAINT ORANGE (-1675 2825);
DISPLAY INVISIBLE (-1675 2825);
FORCEPROP 2 LAST $SEC 1
J 0
(-1675 2925);
PAINT MONO (-1675 2925);
DISPLAY INVISIBLE (-1675 2925);
FORCEPROP 2 LAST CDS_SEC 1
J 0
(-1675 2925);
PAINT MONO (-1675 2925);
DISPLAY INVISIBLE (-1675 2925);
FORCEADD RES..1
(-825 2875);
FORCEPROP 1 LAST WATTAGE 1/16W
J 2
(-850 2725);
DISPLAY 0.617021 (-850 2725);
PAINT SKYBLUE (-850 2725);
FORCEPROP 1 LAST TOLERANCE 5%
J 0
(-875 2775);
DISPLAY 0.617021 (-875 2775);
PAINT SKYBLUE (-875 2775);
FORCEPROP 1 LAST VALUE 0.0
J 2
(-925 2775);
DISPLAY 0.617021 (-925 2775);
PAINT SKYBLUE (-925 2775);
FORCEPROP 1 LAST MATERIAL CHIP
J 0
(-825 2725);
DISPLAY 0.617021 (-825 2725);
PAINT SKYBLUE (-825 2725);
FORCEPROP 1 LAST PART_NUMBER G21497-005
J 0
(-975 2825);
DISPLAY 0.617021 (-975 2825);
PAINT BLUE (-975 2825);
FORCEPROP 1 LAST LOCATION R9M10
J 0
(-875 2925);
DISPLAY 0.617021 (-875 2925);
PAINT AQUA (-875 2925);
FORCEPROP 1 LAST PACK_TYPE 0402
J 0
(-750 2775);
DISPLAY 0.617021 (-750 2775);
PAINT SKYBLUE (-750 2775);
FORCEPROP 1 LAST PATH I88
J 0
(-875 3025);
DISPLAY 0.978723 (-875 3025);
PAINT WHITE (-875 3025);
DISPLAY INVISIBLE (-875 3025);
FORCEPROP 1 LASTPIN (-925 2875) $PN 1
J 0
(-913 2887);
DISPLAY 0.787234 (-913 2887);
PAINT ORANGE (-913 2887);
DISPLAY INVISIBLE (-913 2887);
FORCEPROP 2 LAST ROOM PVCCIN_CPU0_VR
J 0
(-875 2975);
DISPLAY 1.361702 (-875 2975);
PAINT ORANGE (-875 2975);
DISPLAY INVISIBLE (-875 2975);
FORCEPROP 2 LAST CDS_LOCATION R9M10
J 0
(-875 2925);
DISPLAY 0.617021 (-875 2925);
PAINT AQUA (-875 2925);
DISPLAY INVISIBLE (-875 2925);
FORCEPROP 2 LAST CDS_LIB mstr_discrete
J 0
(-825 2875);
PAINT ORANGE (-825 2875);
DISPLAY INVISIBLE (-825 2875);
FORCEPROP 1 LASTPIN (-725 2875) $PN 2
J 0
(-763 2887);
DISPLAY 0.787234 (-763 2887);
PAINT ORANGE (-763 2887);
DISPLAY INVISIBLE (-763 2887);
FORCEPROP 2 LAST $SEC 1
J 0
(-875 3075);
PAINT MONO (-875 3075);
DISPLAY INVISIBLE (-875 3075);
FORCEPROP 2 LAST CDS_SEC 1
J 0
(-875 3075);
PAINT MONO (-875 3075);
DISPLAY INVISIBLE (-875 3075);
FORCEADD OFFPAGE..1
(-2375 2725);
FORCEPROP 2 LAST $XR0 226 
J 0
(-2627 2725);
DISPLAY 0.638298 (-2627 2725);
PAINT MONO (-2627 2725);
FORCEPROP 1 LAST COMMENT_BODY TRUE
J 0
(-2250 2625);
DISPLAY 1.170213 (-2250 2625);
PAINT GREEN (-2250 2625);
DISPLAY INVISIBLE (-2250 2625);
FORCEPROP 1 LAST OFFPAGE TRUE
J 0
(-2050 2600);
DISPLAY 1.170213 (-2050 2600);
PAINT GREEN (-2050 2600);
DISPLAY INVISIBLE (-2050 2600);
FORCEPROP 2 LAST PATH I89
J 0
(-2325 2800);
DISPLAY 1.021277 (-2325 2800);
PAINT ORANGE (-2325 2800);
DISPLAY INVISIBLE (-2325 2800);
FORCEPROP 2 LAST CDS_LIB mstr_standard
J 0
(-2375 2725);
PAINT ORANGE (-2375 2725);
DISPLAY INVISIBLE (-2375 2725);
FORCEPROP 2 LAST ROOM VDDQ_KLM_PWR_VR
J 0
(-2925 2800);
DISPLAY 1.361702 (-2925 2800);
PAINT ORANGE (-2925 2800);
DISPLAY INVISIBLE (-2925 2800);
FORCEADD OFFPAGE..2
(4350 2375);
FORCEPROP 2 LAST $XR2 55 
J 0
(4779 2375);
DISPLAY 0.638298 (4779 2375);
PAINT MONO (4779 2375);
FORCEPROP 2 LAST $XR1 223 
J 0
(4659 2375);
DISPLAY 0.638298 (4659 2375);
PAINT MONO (4659 2375);
FORCEPROP 2 LAST $XR0 193 
J 0
(4539 2375);
DISPLAY 0.638298 (4539 2375);
PAINT MONO (4539 2375);
FORCEPROP 1 LAST COMMENT_BODY TRUE
J 0
(4305 2280);
DISPLAY 1.170213 (4305 2280);
PAINT GREEN (4305 2280);
DISPLAY INVISIBLE (4305 2280);
FORCEPROP 1 LAST OFFPAGE TRUE
J 0
(4675 2250);
DISPLAY 1.170213 (4675 2250);
PAINT GREEN (4675 2250);
DISPLAY INVISIBLE (4675 2250);
FORCEPROP 2 LAST PATH I9
J 0
(4525 2450);
DISPLAY 1.021277 (4525 2450);
PAINT ORANGE (4525 2450);
DISPLAY INVISIBLE (4525 2450);
FORCEPROP 2 LAST CDS_LIB mstr_standard
J 0
(4350 2375);
PAINT ORANGE (4350 2375);
DISPLAY INVISIBLE (4350 2375);
FORCEPROP 2 LAST ROOM VDDQ_KLM_PWR_VR
J 0
(3925 2450);
DISPLAY 1.361702 (3925 2450);
PAINT ORANGE (3925 2450);
DISPLAY INVISIBLE (3925 2450);
FORCEADD PXM1310B..2
(1425 1775);
FORCEPROP 2 LASTPIN (1875 2525) $PN 9
J 0
(1885 2535);
DISPLAY 0.617021 (1885 2535);
PAINT ORANGE (1885 2535);
FORCEPROP 2 LASTPIN (1875 2375) $PN 17
J 0
(1885 2385);
DISPLAY 0.617021 (1885 2385);
PAINT ORANGE (1885 2385);
FORCEPROP 2 LASTPIN (1875 2425) $PN 11
J 0
(1885 2435);
DISPLAY 0.617021 (1885 2435);
PAINT ORANGE (1885 2435);
FORCEPROP 2 LASTPIN (1875 2125) $PN 12
J 0
(1885 2135);
DISPLAY 0.617021 (1885 2135);
PAINT ORANGE (1885 2135);
FORCEPROP 2 LASTPIN (1875 2225) $PN 18
J 0
(1885 2235);
DISPLAY 0.617021 (1885 2235);
PAINT ORANGE (1885 2235);
FORCEPROP 1 LAST MATERIAL IC
J 0
(1025 2700);
DISPLAY 0.617021 (1025 2700);
PAINT SKYBLUE (1025 2700);
FORCEPROP 1 LAST LOCATION EU1B1
J 0
(1025 2750);
DISPLAY 0.617021 (1025 2750);
PAINT AQUA (1025 2750);
FORCEPROP 2 LASTPIN (975 2525) $PN 39
J 2
(965 2535);
DISPLAY 0.617021 (965 2535);
PAINT ORANGE (965 2535);
FORCEPROP 2 LASTPIN (975 2425) $PN 15
J 2
(965 2435);
DISPLAY 0.617021 (965 2435);
PAINT ORANGE (965 2435);
FORCEPROP 2 LASTPIN (975 2325) $PN 21
J 2
(965 2335);
DISPLAY 0.617021 (965 2335);
PAINT ORANGE (965 2335);
FORCEPROP 2 LASTPIN (975 2275) $PN 23
J 2
(965 2285);
DISPLAY 0.617021 (965 2285);
PAINT ORANGE (965 2285);
FORCEPROP 2 LASTPIN (975 2225) $PN 25
J 2
(965 2235);
DISPLAY 0.617021 (965 2235);
PAINT ORANGE (965 2235);
FORCEPROP 2 LASTPIN (975 2125) $PN 22
J 2
(965 2135);
DISPLAY 0.617021 (965 2135);
PAINT ORANGE (965 2135);
FORCEPROP 2 LASTPIN (975 2075) $PN 24
J 2
(965 2085);
DISPLAY 0.617021 (965 2085);
PAINT ORANGE (965 2085);
FORCEPROP 2 LASTPIN (1875 2025) $PN 7
J 0
(1885 2035);
DISPLAY 0.617021 (1885 2035);
PAINT ORANGE (1885 2035);
FORCEPROP 2 LASTPIN (975 2025) $PN 26
J 2
(965 2035);
DISPLAY 0.617021 (965 2035);
PAINT ORANGE (965 2035);
FORCEPROP 2 LASTPIN (1875 1975) $PN 6
J 0
(1885 1985);
DISPLAY 0.617021 (1885 1985);
PAINT ORANGE (1885 1985);
FORCEPROP 2 LASTPIN (1875 1825) $PN 14
J 0
(1885 1835);
DISPLAY 0.617021 (1885 1835);
PAINT ORANGE (1885 1835);
FORCEPROP 2 LASTPIN (1875 1875) $PN 13
J 0
(1885 1885);
DISPLAY 0.617021 (1885 1885);
PAINT ORANGE (1885 1885);
FORCEPROP 2 LASTPIN (1875 1725) $PN 40
J 0
(1885 1735);
DISPLAY 0.617021 (1885 1735);
PAINT ORANGE (1885 1735);
FORCEPROP 2 LASTPIN (1875 1675) $PN 16
J 0
(1885 1685);
DISPLAY 0.617021 (1885 1685);
PAINT ORANGE (1885 1685);
FORCEPROP 2 LASTPIN (1875 1525) $PN 1
J 0
(1885 1535);
DISPLAY 0.617021 (1885 1535);
PAINT ORANGE (1885 1535);
FORCEPROP 2 LASTPIN (1875 1375) $PN 3
J 0
(1885 1385);
DISPLAY 0.617021 (1885 1385);
PAINT ORANGE (1885 1385);
FORCEPROP 2 LASTPIN (1875 1425) $PN 4
J 0
(1885 1435);
DISPLAY 0.617021 (1885 1435);
PAINT ORANGE (1885 1435);
FORCEPROP 2 LASTPIN (1875 1475) $PN 5
J 0
(1885 1485);
DISPLAY 0.617021 (1885 1485);
PAINT ORANGE (1885 1485);
FORCEPROP 2 LASTPIN (1875 1075) $PN 41
J 0
(1885 1085);
DISPLAY 0.617021 (1885 1085);
PAINT ORANGE (1885 1085);
FORCEPROP 2 LASTPIN (1875 1225) $PN 28
J 0
(1885 1235);
DISPLAY 0.617021 (1885 1235);
PAINT ORANGE (1885 1235);
FORCEPROP 2 LASTPIN (1875 1175) $PN 2
J 0
(1885 1185);
DISPLAY 0.617021 (1885 1185);
PAINT ORANGE (1885 1185);
FORCEPROP 2 LASTPIN (1875 975) $PN 27
J 0
(1885 985);
DISPLAY 0.617021 (1885 985);
PAINT ORANGE (1885 985);
FORCEPROP 1 LAST PART_NUMBER H89186-001
J 0
(1025 825);
DISPLAY 0.617021 (1025 825);
PAINT BLUE (1025 825);
FORCEPROP 2 LASTPIN (975 1875) $PN 38
J 2
(965 1885);
DISPLAY 0.617021 (965 1885);
PAINT ORANGE (965 1885);
FORCEPROP 2 LASTPIN (975 1925) $PN 37
J 2
(965 1935);
DISPLAY 0.617021 (965 1935);
PAINT ORANGE (965 1935);
FORCEPROP 2 LASTPIN (975 1775) $PN 35
J 2
(965 1785);
DISPLAY 0.617021 (965 1785);
PAINT ORANGE (965 1785);
FORCEPROP 2 LASTPIN (975 1575) $PN 29
J 2
(965 1585);
DISPLAY 0.617021 (965 1585);
PAINT ORANGE (965 1585);
FORCEPROP 2 LASTPIN (975 1725) $PN 34
J 2
(965 1735);
DISPLAY 0.617021 (965 1735);
PAINT ORANGE (965 1735);
FORCEPROP 2 LASTPIN (975 1625) $PN 19
J 2
(965 1635);
DISPLAY 0.617021 (965 1635);
PAINT ORANGE (965 1635);
FORCEPROP 2 LASTPIN (975 1325) $PN 30
J 2
(965 1335);
DISPLAY 0.617021 (965 1335);
PAINT ORANGE (965 1335);
FORCEPROP 2 LASTPIN (975 1475) $PN 10
J 2
(965 1485);
DISPLAY 0.617021 (965 1485);
PAINT ORANGE (965 1485);
FORCEPROP 2 LASTPIN (975 1375) $PN 20
J 2
(965 1385);
DISPLAY 0.617021 (965 1385);
PAINT ORANGE (965 1385);
FORCEPROP 2 LASTPIN (975 1125) $PN 31
J 2
(965 1135);
DISPLAY 0.617021 (965 1135);
PAINT ORANGE (965 1135);
FORCEPROP 2 LASTPIN (975 1075) $PN 32
J 2
(965 1085);
DISPLAY 0.617021 (965 1085);
PAINT ORANGE (965 1085);
FORCEPROP 2 LASTPIN (975 1225) $PN 8
J 2
(965 1235);
DISPLAY 0.617021 (965 1235);
PAINT ORANGE (965 1235);
FORCEPROP 2 LASTPIN (975 925) $PN 33
J 2
(965 935);
DISPLAY 0.617021 (965 935);
PAINT ORANGE (965 935);
FORCEPROP 2 LASTPIN (975 975) $PN 36
J 2
(965 985);
DISPLAY 0.617021 (965 985);
PAINT ORANGE (965 985);
FORCEPROP 1 LAST PATH I90
J 0
(1525 2701);
PAINT WHITE (1525 2701);
DISPLAY INVISIBLE (1525 2701);
FORCEPROP 2 LAST SEC 1
J 0
(1025 2800);
DISPLAY 0.680851 (1025 2800);
PAINT MONO (1025 2800);
DISPLAY INVISIBLE (1025 2800);
FORCEPROP 2 LAST SEC_TYPE QFN
J 0
(1025 2800);
DISPLAY 1.021277 (1025 2800);
PAINT ORANGE (1025 2800);
DISPLAY INVISIBLE (1025 2800);
FORCEPROP 1 LAST PACK_TYPE QFN
J 0
(1025 2800);
PAINT SKYBLUE (1025 2800);
DISPLAY INVISIBLE (1025 2800);
FORCEPROP 2 LAST CDS_LOCATION EU1B1
J 0
(1025 2750);
PAINT WHITE (1025 2750);
DISPLAY INVISIBLE (1025 2750);
FORCEPROP 2 LAST CDS_LIB mstr_controller
J 0
(1425 1775);
PAINT ORANGE (1425 1775);
DISPLAY INVISIBLE (1425 1775);
FORCEPROP 1 LAST CDS_LMAN_SYM_OUTLINE -400,900,400,-900
J 0
(1425 1775);
DISPLAY 0.468085 (1425 1775);
PAINT GREEN (1425 1775);
DISPLAY INVISIBLE (1425 1775);
FORCEADD GND..1
(-425 50);
FORCEPROP 3 LASTPIN (-425 100) SIG_NAME GND\g
J 0
(-415 110);
DISPLAY 0.659574 (-415 110);
PAINT MONO (-415 110);
DISPLAY INVISIBLE (-415 110);
FORCEPROP 1 LAST HDL_POWER GND
J 0
(-425 200);
DISPLAY 1.170213 (-425 200);
PAINT GREEN (-425 200);
DISPLAY INVISIBLE (-425 200);
FORCEPROP 1 LAST BODY_TYPE PLUMBING
J 0
(-470 7);
DISPLAY 0.340426 (-470 7);
PAINT GREEN (-470 7);
DISPLAY INVISIBLE (-470 7);
FORCEPROP 2 LAST CDS_LIB mstr_symbols
J 0
(-425 50);
PAINT ORANGE (-425 50);
DISPLAY INVISIBLE (-425 50);
FORCEPROP 1 LAST VOLTAGE 0.0V
J 0
(-470 7);
DISPLAY 0.340426 (-470 7);
PAINT SKYBLUE (-470 7);
DISPLAY INVISIBLE (-470 7);
FORCEPROP 1 LAST PATH I91
J 0
(-350 50);
DISPLAY 0.872340 (-350 50);
PAINT AQUA (-350 50);
DISPLAY INVISIBLE (-350 50);
FORCEPROP 1 LAST SIZE 1B
J 0
(-350 0);
DISPLAY 1.170213 (-350 0);
PAINT AQUA (-350 0);
DISPLAY INVISIBLE (-350 0);
FORCEADD CAP_A..1
R 2
(-425 425);
FORCEPROP 1 LASTPIN (-425 525) $PN 1
J 2
(-435 505);
DISPLAY 0.617021 (-435 505);
PAINT ORANGE (-435 505);
FORCEPROP 1 LASTPIN (-425 325) $PN 2
J 2
(-435 305);
DISPLAY 0.617021 (-435 305);
PAINT ORANGE (-435 305);
FORCEPROP 1 LAST LOCATION C9M11
J 2
(-475 525);
DISPLAY 0.617021 (-475 525);
PAINT AQUA (-475 525);
FORCEPROP 1 LAST PART_NUMBER A36096-030
J 2
(-475 275);
DISPLAY 0.617021 (-475 275);
PAINT BLUE (-475 275);
FORCEPROP 1 LAST VALUE 0.1UF
J 2
(-475 475);
DISPLAY 0.617021 (-475 475);
PAINT SKYBLUE (-475 475);
FORCEPROP 1 LAST TOLERANCE 10%
J 2
(-475 375);
DISPLAY 0.617021 (-475 375);
PAINT SKYBLUE (-475 375);
FORCEPROP 1 LAST PACK_TYPE 0402V
J 2
(-475 225);
DISPLAY 0.617021 (-475 225);
PAINT SKYBLUE (-475 225);
FORCEPROP 1 LAST VOLTAGE 16V
J 2
(-475 425);
DISPLAY 0.617021 (-475 425);
PAINT SKYBLUE (-475 425);
FORCEPROP 1 LAST MATERIAL X7R
J 2
(-475 325);
DISPLAY 0.617021 (-475 325);
PAINT SKYBLUE (-475 325);
FORCEPROP 2 LAST SEC 1
J 0
(-475 625);
DISPLAY 0.680851 (-475 625);
PAINT MONO (-475 625);
DISPLAY INVISIBLE (-475 625);
FORCEPROP 2 LAST SEC_TYPE 0402V
J 0
(-475 625);
DISPLAY 1.021277 (-475 625);
PAINT ORANGE (-475 625);
DISPLAY INVISIBLE (-475 625);
FORCEPROP 2 LAST CDS_SEC 1
J 0
(-475 575);
PAINT ORANGE (-475 575);
DISPLAY INVISIBLE (-475 575);
FORCEPROP 0 LAST ROOM VDDQ_KLM_PWR_VR
J 0
(-475 575);
DISPLAY 1.021277 (-475 575);
PAINT ORANGE (-475 575);
DISPLAY INVISIBLE (-475 575);
FORCEPROP 1 LAST PATH I92
J 2
(-475 575);
DISPLAY 0.978723 (-475 575);
PAINT WHITE (-475 575);
DISPLAY INVISIBLE (-475 575);
FORCEPROP 2 LAST CDS_LIB dev_discrete
J 0
(-425 425);
PAINT ORANGE (-425 425);
DISPLAY INVISIBLE (-425 425);
FORCEADD DNS..2
(3805 2770);
PAINT RED (3805 2770);
FORCEPROP 1 LAST COMMENT_BODY TRUE
R 1
J 0
(3880 2545);
DISPLAY 0.872340 (3880 2545);
PAINT GREEN (3880 2545);
DISPLAY INVISIBLE (3880 2545);
FORCEPROP 2 LAST CDS_LIB mstr_misc
J 0
(3805 2770);
PAINT ORANGE (3805 2770);
DISPLAY INVISIBLE (3805 2770);
FORCEADD DESIGN_NOTE..1
(4250 3900);
PAINT PURPLE (4250 3900);
FORCEPROP 0 LAST L1 SMBUS ADDRESS 0X74
J 0
(4075 3775);
PAINT VIOLET (4075 3775);
FORCEPROP 0 LAST L2 SVID ADDRESS=0X2
J 0
(4080 3715);
DISPLAY 1.021277 (4080 3715);
PAINT ORANGE (4080 3715);
FORCEPROP 1 LAST COMMENT_BODY TRUE
J 0
(4275 4000);
DISPLAY 1.319149 (4275 4000);
PAINT GREEN (4275 4000);
DISPLAY INVISIBLE (4275 4000);
FORCEPROP 2 LAST CDS_LIB mstr_symbols
J 0
(4250 3900);
PAINT MONO (4250 3900);
DISPLAY INVISIBLE (4250 3900);
FORCEPROP 2 LAST BOM_COST VDDQ_KLM_VR
J 0
(4050 3850);
PAINT MONO (4050 3850);
DISPLAY INVISIBLE (4050 3850);
FORCEPROP 2 LAST ROOM VDDQ_KLM_PWR_VR
J 0
(4050 3850);
PAINT MONO (4050 3850);
DISPLAY INVISIBLE (4050 3850);
FORCEADD DESIGN_NOTE..1
(900 700);
FORCEPROP 0 LAST L2 SVID ADDRESS=0X2
J 0
(705 515);
DISPLAY 1.021277 (705 515);
PAINT ORANGE (705 515);
FORCEPROP 0 LAST L1 SMBUS ADDRESS: 0X74
J 0
(700 575);
DISPLAY 1.021277 (700 575);
PAINT ORANGE (700 575);
FORCEPROP 1 LAST COMMENT_BODY TRUE
J 0
(925 800);
DISPLAY 0.978723 (925 800);
PAINT ORANGE (925 800);
DISPLAY INVISIBLE (925 800);
FORCEPROP 2 LAST CDS_LIB mstr_symbols
J 0
(900 700);
PAINT ORANGE (900 700);
DISPLAY INVISIBLE (900 700);
FORCEADD DNS..2
(80 3545);
PAINT RED (80 3545);
FORCEPROP 1 LAST COMMENT_BODY TRUE
R 1
J 0
(155 3320);
DISPLAY 0.872340 (155 3320);
PAINT GREEN (155 3320);
DISPLAY INVISIBLE (155 3320);
FORCEPROP 2 LAST CDS_LIB mstr_misc
J 0
(80 3545);
PAINT ORANGE (80 3545);
DISPLAY INVISIBLE (80 3545);
FORCEADD DNS..2
(2755 3045);
PAINT RED (2755 3045);
FORCEPROP 1 LAST COMMENT_BODY TRUE
R 1
J 0
(2830 2820);
DISPLAY 0.872340 (2830 2820);
PAINT GREEN (2830 2820);
DISPLAY INVISIBLE (2830 2820);
FORCEPROP 2 LAST CDS_LIB mstr_misc
J 0
(2755 3045);
PAINT ORANGE (2755 3045);
DISPLAY INVISIBLE (2755 3045);
FORCEADD INTEL_CORP_BPAGE..1
(5250 -875);
FORCEPROP 1 LAST CDS_CON_LAST_MODIFIED Tue Dec 01 11:52:27 2015
J 0
(3825 -550);
DISPLAY 0.744681 (3825 -550);
PAINT GREEN (3825 -550);
DISPLAY INVISIBLE (3825 -550);
FORCEPROP 1 LAST CUSTOM_TXT_CDS <CURRENT_DESIGN_SHEET> OF <TOTAL_DESIGN_SHEETS>
J 0
(4750 -850);
PAINT GREEN (4750 -850);
FORCEPROP 1 LAST CUSTOM_TXT_CDS <CON_LAST_MODIFIED>
J 0
(3325 -525);
PAINT GREEN (3325 -525);
FORCEPROP 2 LAST CUSTOM_TXT_CDS <XR_PAGE_TITLE>
J 0
(-2640 4375);
DISPLAY 0.638298 (-2640 4375);
PAINT PINK (-2640 4375);
DISPLAY INVISIBLE (-2640 4375);
FORCEPROP 1 LAST SCH_REV 2.420
J 0
(5000 -725);
DISPLAY 0.978723 (5000 -725);
PAINT YELLOW (5000 -725);
FORCEPROP 1 LAST SCH_DEPT BESD
J 1
(800 -775);
DISPLAY 1.212766 (800 -775);
PAINT YELLOW (800 -775);
FORCEPROP 1 LAST SCH_NUMBER H4694802
J 0
(3950 -725);
DISPLAY 1.212766 (3950 -725);
PAINT YELLOW (3950 -725);
FORCEPROP 1 LAST SCH_ADDRESS3 Santa Clara, CA 95052-8119
J 0
(1275 -850);
DISPLAY 0.617021 (1275 -850);
PAINT GREEN (1275 -850);
FORCEPROP 1 LAST SCH_ADDRESS2 P.O. BOX 58119
J 0
(1275 -800);
DISPLAY 0.617021 (1275 -800);
PAINT GREEN (1275 -800);
FORCEPROP 1 LAST SCH_ADDRESS1 2200 Mission College Blvd.
J 0
(1275 -750);
DISPLAY 0.617021 (1275 -750);
PAINT GREEN (1275 -750);
FORCEPROP 1 LAST SCH_TITLE VDDQ KLM_VR (1 OF 3)
J 0
(-2725 -850);
DISPLAY 1.212766 (-2725 -850);
PAINT ORANGE (-2725 -850);
FORCEPROP 1 LAST COMMENT_BODY TRUE
J 0
(5262 -863);
DISPLAY 0.340426 (5262 -863);
PAINT GREEN (5262 -863);
DISPLAY INVISIBLE (5262 -863);
FORCEPROP 2 LAST ROOM VDDQ_KLM_PWR_VR
J 0
(4800 4275);
DISPLAY 0.744681 (4800 4275);
PAINT ORANGE (4800 4275);
DISPLAY INVISIBLE (4800 4275);
FORCEPROP 2 LAST CDS_LIB mstr_symbols
J 0
(5250 -875);
DISPLAY 0.744681 (5250 -875);
PAINT ORANGE (5250 -875);
DISPLAY INVISIBLE (5250 -875);
FORCEPROP 2 LAST PAGE_BORDER TRUE
J 0
(-2640 4375);
DISPLAY 0.638298 (-2640 4375);
PAINT PINK (-2640 4375);
DISPLAY INVISIBLE (-2640 4375);
FORCEPROP 2 LAST CDS_XR_PAGE_TITLE CR-226 : @BASEBOARD_FAB2_LIB.BASEBOARD_FAB2(SCH_1):PAGE226
J 0
(-2640 4375);
DISPLAY 0.638298 (-2640 4375);
PAINT PINK (-2640 4375);
DISPLAY INVISIBLE (-2640 4375);
WIRE 16 -1 (2075 3125)(2075 3525);
WIRE 16 -1 (2075 3525)(2350 3525);
WIRE 16 -1 (2350 3125)(2350 3525);
WIRE 16 -1 (2450 3525)(2350 3525);
WIRE 16 -1 (2750 3525)(2450 3525);
WIRE 16 -1 (2450 3525)(2450 3650);
WIRE 16 -1 (2750 3150)(2750 3525);
WIRE 16 -1 (1875 1075)(2000 1075);
WIRE 16 -1 (2000 1075)(2000 975);
WIRE 16 -1 (1875 975)(2000 975);
WIRE 16 -1 (2000 850)(2000 975);
WIRE 16 -1 (1525 2925)(1525 2975);
WIRE 16 -1 (1125 2925)(1125 2975);
WIRE 16 -1 (825 3625)(825 3775);
WIRE 16 -1 (825 3775)(500 3775);
WIRE 16 -1 (75 3775)(500 3775);
WIRE 16 -1 (500 3775)(500 3900);
WIRE 16 -1 (75 3650)(75 3775);
WIRE 16 -1 (975 1075)(100 1075);
WIRE 16 -1 (100 1075)(100 875);
WIRE 16 -1 (3750 -125)(3750 50);
WIRE 16 -1 (3350 25)(3350 75);
WIRE 16 -1 (575 75)(575 175);
WIRE 16 -1 (200 75)(200 175);
WIRE 16 -1 (25 75)(25 625);
WIRE 16 -1 (-675 3650)(-675 3850);
WIRE 16 -1 (-1250 3825)(-1250 3925);
WIRE 16 -1 (-1250 3150)(-1250 3225);
WIRE 16 -1 (-1475 3200)(-1475 3275);
WIRE 16 -1 (3800 2875)(3800 2950);
WIRE 16 -1 (2900 875)(2900 750);
WIRE 16 -1 (-425 100)(-425 325);
WIRE 16 -1 (-1250 3550)(-1250 3625);
WIRE 16 -1 (-1250 3425)(-1250 3550);
WIRE 16 -1 (-1250 3550)(-1475 3550);
WIRE 16 -1 (-1475 3475)(-1475 3550);
WIRE 16 -1 (-1475 3550)(-2225 3550);
FORCEPROP 2 LAST SIG_NAME VR_PVDDQ_KLM_VINSEN
J 0
(-2240 3565);
DISPLAY 0.617021 (-2240 3565);
PAINT ORANGE (-2240 3565);
WIRE 16 -1 (-1825 2875)(-925 2875);
WIRE 16 -1 (-1825 2725)(-1825 2875);
WIRE 16 -1 (-1825 2725)(-1725 2725);
WIRE 16 -1 (-2325 2725)(-1825 2725);
FORCEPROP 2 LAST SIG_NAME VR_PVDDQ_KLM_VD12
J 0
(-2290 2740);
DISPLAY 0.617021 (-2290 2740);
PAINT ORANGE (-2290 2740);
WIRE 16 -1 (-725 2875)(-600 2875);
WIRE 16 -1 (-600 2875)(-600 2275);
WIRE 16 -1 (975 2275)(-600 2275);
WIRE 16 -1 (-2200 2275)(-600 2275);
FORCEPROP 2 LAST SIG_NAME VR_PVDDQ_KLM_AIREF2
J 0
(-2115 2290);
DISPLAY 0.617021 (-2115 2290);
PAINT ORANGE (-2115 2290);
WIRE 16 -1 (-1525 2725)(-1400 2725);
WIRE 16 -1 (-1400 2725)(-1400 2325);
WIRE 16 -1 (-1400 2325)(975 2325);
WIRE 16 -1 (-2200 2325)(-1400 2325);
FORCEPROP 2 LAST SIG_NAME VR_PVDDQ_KLM_AIREF1
J 0
(-2140 2340);
DISPLAY 0.617021 (-2140 2340);
PAINT ORANGE (-2140 2340);
WIRE 16 -1 (-1650 1475)(-2200 1475);
FORCEPROP 2 LAST SIG_NAME FM_PVDDQ_KLM_EN
J 0
(-2200 1485);
DISPLAY 0.617021 (-2200 1485);
PAINT ORANGE (-2200 1485);
WIRE 16 -1 (-1450 1475)(75 1475);
FORCEPROP 2 LAST SIG_NAME VR_PVDDQ_KLM_VREN
J 0
(-1310 1475);
DISPLAY 0.617021 (-1310 1475);
PAINT ORANGE (-1310 1475);
FORCEPROP 2 LASTPROP $XRERR UNIQUE?
J 0
(-1550 1475);
DISPLAY 0.638298 (-1550 1475);
PAINT MONO (-1550 1475);
DISPLAY INVISIBLE (-1550 1475);
WIRE 16 -1 (75 1475)(75 3450);
WIRE 16 -1 (75 1475)(975 1475);
WIRE 16 -1 (3175 2425)(2075 2425);
FORCEPROP 2 LAST SIG_NAME IRQ_PVDDQ_KLM_VRHOT_LVT3_R_N
J 0
(1985 2440);
DISPLAY 0.617021 (1985 2440);
PAINT ORANGE (1985 2440);
FORCEPROP 2 LASTPROP $XRERR UNIQUE?
J 0
(1745 2440);
DISPLAY 0.638298 (1745 2440);
PAINT MONO (1745 2440);
DISPLAY INVISIBLE (1745 2440);
WIRE 16 -1 (2075 2925)(2075 2425);
WIRE 16 -1 (2075 2425)(1875 2425);
WIRE 16 -1 (4300 2425)(3375 2425);
FORCEPROP 2 LAST SIG_NAME IRQ_PVDDQ_KLM_VRHOT_LVT3_N
J 0
(3460 2440);
DISPLAY 0.617021 (3460 2440);
PAINT ORANGE (3460 2440);
WIRE 16 -1 (-400 3050)(-675 3050);
WIRE 16 -1 (-675 3450)(-675 3050);
WIRE 16 -1 (-2225 3050)(-675 3050);
FORCEPROP 0 LAST SIG_NAME SVID_CLK1_CPU1_R
J 0
(-2225 3060);
DISPLAY 0.617021 (-2225 3060);
PAINT ORANGE (-2225 3060);
WIRE 16 -1 (650 3050)(650 2425);
WIRE 16 -1 (-200 3050)(650 3050);
FORCEPROP 2 LAST SIG_NAME SVID_CLK_PVDDQ_KLM
J 0
(160 3065);
DISPLAY 0.617021 (160 3065);
PAINT ORANGE (160 3065);
FORCEPROP 2 LASTPROP $XRERR UNIQUE?
J 0
(-80 3065);
DISPLAY 0.638298 (-80 3065);
PAINT MONO (-80 3065);
DISPLAY INVISIBLE (-80 3065);
WIRE 16 -1 (650 2425)(975 2425);
WIRE 16 -1 (-1775 1175)(-2200 1175);
FORCEPROP 2 LAST SIG_NAME VSENSE_PVDDQ_KLM_P
J 0
(-2215 1190);
DISPLAY 0.617021 (-2215 1190);
PAINT ORANGE (-2215 1190);
WIRE 16 -1 (-1575 1175)(-1500 1175);
WIRE 16 -1 (-1500 1175)(-625 1175);
FORCEPROP 2 LAST SIG_NAME VR_PVDDQ_KLM_AVSP
J 0
(-1465 1190);
DISPLAY 0.617021 (-1465 1190);
PAINT ORANGE (-1465 1190);
FORCEPROP 2 LASTPROP $XRERR UNIQUE?
J 0
(-1705 1190);
DISPLAY 0.638298 (-1705 1190);
PAINT MONO (-1705 1190);
DISPLAY INVISIBLE (-1705 1190);
WIRE 16 -1 (-1500 1125)(-1500 1175);
WIRE 16 -1 (-625 1175)(-625 1625);
WIRE 16 -1 (975 1625)(-625 1625);
WIRE 16 -1 (1875 1675)(2675 1675);
FORCEPROP 2 LAST SIG_NAME SVID_VDIO_PVDDQ_KLM
J 0
(1975 1690);
DISPLAY 0.617021 (1975 1690);
PAINT ORANGE (1975 1690);
FORCEPROP 2 LASTPROP $XRERR UNIQUE?
J 0
(1735 1690);
DISPLAY 0.638298 (1735 1690);
PAINT MONO (1735 1690);
DISPLAY INVISIBLE (1735 1690);
WIRE 16 -1 (2875 1675)(3800 1675);
FORCEPROP 2 LAST SIG_NAME SVID_DIO1_CPU1_R
J 0
(3325 1685);
DISPLAY 0.617021 (3325 1685);
PAINT ORANGE (3325 1685);
WIRE 16 -1 (3800 2675)(3800 1675);
WIRE 16 -1 (3800 1675)(3975 1675);
WIRE 16 -1 (1875 1975)(2675 1975);
FORCEPROP 2 LAST SIG_NAME SMB_VR_SDA_VDDQ_KLM
J 0
(1975 1990);
DISPLAY 0.617021 (1975 1990);
PAINT ORANGE (1975 1990);
FORCEPROP 2 LASTPROP $XRERR UNIQUE?
J 0
(1735 1990);
DISPLAY 0.638298 (1735 1990);
PAINT MONO (1735 1990);
DISPLAY INVISIBLE (1735 1990);
WIRE 16 -1 (2875 1975)(3975 1975);
FORCEPROP 2 LAST SIG_NAME SMB_VR_STBY_LVC3_SDA
J 0
(3310 1990);
DISPLAY 0.617021 (3310 1990);
PAINT ORANGE (3310 1990);
WIRE 16 -1 (1875 2025)(3000 2025);
FORCEPROP 2 LAST SIG_NAME SMB_VR_SCL_VDDQ_KLM
J 0
(1975 2040);
DISPLAY 0.617021 (1975 2040);
PAINT ORANGE (1975 2040);
FORCEPROP 2 LASTPROP $XRERR UNIQUE?
J 0
(1735 2040);
DISPLAY 0.638298 (1735 2040);
PAINT MONO (1735 2040);
DISPLAY INVISIBLE (1735 2040);
WIRE 16 -1 (3200 2025)(3975 2025);
FORCEPROP 2 LAST SIG_NAME SMB_VR_STBY_LVC3_SCL
J 0
(3260 2040);
DISPLAY 0.617021 (3260 2040);
PAINT ORANGE (3260 2040);
WIRE 16 -1 (2475 2375)(1875 2375);
FORCEPROP 2 LAST SIG_NAME SVID_ALERT_PVDDQ_KLM
J 0
(1975 2390);
DISPLAY 0.617021 (1975 2390);
PAINT ORANGE (1975 2390);
FORCEPROP 2 LASTPROP $XRERR UNIQUE?
J 0
(1735 2390);
DISPLAY 0.638298 (1735 2390);
PAINT MONO (1735 2390);
DISPLAY INVISIBLE (1735 2390);
WIRE 16 -1 (4300 2375)(2675 2375);
FORCEPROP 2 LAST SIG_NAME SVID_ALERT1_CPU1_R_N
J 0
(3600 2385);
DISPLAY 0.617021 (3600 2385);
PAINT ORANGE (3600 2385);
WIRE 16 -1 (3275 2525)(2900 2525);
WIRE 16 -1 (2900 2525)(2350 2525);
FORCEPROP 2 LAST SIG_NAME PWRGD_PVDDQ_KLM_R
J 0
(2510 2540);
DISPLAY 0.617021 (2510 2540);
PAINT ORANGE (2510 2540);
FORCEPROP 2 LASTPROP $XRERR UNIQUE?
J 0
(2270 2540);
DISPLAY 0.638298 (2270 2540);
PAINT MONO (2270 2540);
DISPLAY INVISIBLE (2270 2540);
WIRE 16 -1 (2900 2525)(2900 1075);
WIRE 16 -1 (2350 2925)(2350 2525);
WIRE 16 -1 (1875 2525)(2350 2525);
WIRE 16 -1 (3475 2525)(4300 2525);
FORCEPROP 2 LAST SIG_NAME PWRGD_PVDDQ_KLM
J 0
(3585 2540);
DISPLAY 0.617021 (3585 2540);
PAINT ORANGE (3585 2540);
WIRE 16 2175 (4850 3600)(4850 3100);
WIRE 16 2175 (4850 3600)(3925 3600);
WIRE 16 2175 (4850 3100)(3925 3100);
WIRE 16 2175 (3925 3100)(3925 3600);
WIRE 16 -1 (3350 275)(3350 350);
WIRE 16 -1 (3750 350)(3350 350);
FORCEPROP 2 LAST SIG_NAME VR_PVDDQ_KLM_VD12
J 0
(3435 365);
DISPLAY 0.617021 (3435 365);
PAINT ORANGE (3435 365);
WIRE 16 -1 (3750 350)(4300 350);
WIRE 16 -1 (3750 250)(3750 350);
WIRE 16 -1 (1875 1875)(2650 1875);
FORCEPROP 2 LAST SIG_NAME PU_VR_PVDDQ_KLM_FAULT1
J 0
(1960 1890);
DISPLAY 0.617021 (1960 1890);
PAINT ORANGE (1960 1890);
FORCEPROP 2 LASTPROP $XRERR UNIQUE?
J 0
(1720 1890);
DISPLAY 0.638298 (1720 1890);
PAINT MONO (1720 1890);
DISPLAY INVISIBLE (1720 1890);
WIRE 16 -1 (2650 1875)(2650 2200);
WIRE 16 -1 (2650 2200)(2750 2200);
WIRE 16 -1 (2750 2950)(2750 2200);
WIRE 16 -1 (1875 2225)(2525 2225);
FORCEPROP 2 LAST SIG_NAME NC_PVDDQ_KLM_GP0
J 0
(2000 2240);
DISPLAY 0.617021 (2000 2240);
PAINT ORANGE (2000 2240);
FORCEPROP 2 LASTPROP $XRERR UNIQUE?
J 0
(2555 2225);
DISPLAY 0.638298 (2555 2225);
PAINT MONO (2555 2225);
DISPLAY INVISIBLE (2555 2225);
WIRE 16 -1 (1875 1525)(2575 1525);
FORCEPROP 2 LAST SIG_NAME TP_PVDDQ_KLM_BPWM1
J 0
(1975 1540);
DISPLAY 0.617021 (1975 1540);
PAINT ORANGE (1975 1540);
FORCEPROP 2 LASTPROP $XRERR UNIQUE?
J 0
(2605 1525);
DISPLAY 0.638298 (2605 1525);
PAINT MONO (2605 1525);
DISPLAY INVISIBLE (2605 1525);
WIRE 16 -1 (1875 1375)(2675 1375);
FORCEPROP 2 LAST SIG_NAME NC_PVDDQ_KLM_PWM3
J 0
(1975 1390);
DISPLAY 0.617021 (1975 1390);
PAINT ORANGE (1975 1390);
FORCEPROP 2 LASTPROP $XRERR UNIQUE?
J 0
(2705 1375);
DISPLAY 0.638298 (2705 1375);
PAINT MONO (2705 1375);
DISPLAY INVISIBLE (2705 1375);
WIRE 16 -1 (1875 1175)(2575 1175);
FORCEPROP 2 LAST SIG_NAME NC_PVDDQ_KLM_DNC0
J 0
(1975 1190);
DISPLAY 0.617021 (1975 1190);
PAINT ORANGE (1975 1190);
FORCEPROP 2 LASTPROP $XRERR UNIQUE?
J 0
(2605 1175);
DISPLAY 0.638298 (2605 1175);
PAINT MONO (2605 1175);
DISPLAY INVISIBLE (2605 1175);
WIRE 16 -1 (1875 1225)(2575 1225);
FORCEPROP 2 LAST SIG_NAME NC_PVDDQ_KLM_DNC1
J 0
(1975 1240);
DISPLAY 0.617021 (1975 1240);
PAINT ORANGE (1975 1240);
FORCEPROP 2 LASTPROP $XRERR UNIQUE?
J 0
(2605 1225);
DISPLAY 0.638298 (2605 1225);
PAINT MONO (2605 1225);
DISPLAY INVISIBLE (2605 1225);
WIRE 16 -1 (1875 2125)(2575 2125);
FORCEPROP 2 LAST SIG_NAME NC_PVDDQ_KLM_PINALRT_N
J 0
(1975 2140);
DISPLAY 0.617021 (1975 2140);
PAINT ORANGE (1975 2140);
FORCEPROP 2 LASTPROP $XRERR UNIQUE?
J 0
(2605 2125);
DISPLAY 0.638298 (2605 2125);
PAINT MONO (2605 2125);
DISPLAY INVISIBLE (2605 2125);
WIRE 16 -1 (1875 1825)(2575 1825);
FORCEPROP 2 LAST SIG_NAME NC_PVDDQ_KLM_GP1
J 0
(1975 1840);
DISPLAY 0.617021 (1975 1840);
PAINT ORANGE (1975 1840);
FORCEPROP 2 LASTPROP $XRERR UNIQUE?
J 0
(2605 1825);
DISPLAY 0.638298 (2605 1825);
PAINT MONO (2605 1825);
DISPLAY INVISIBLE (2605 1825);
WIRE 16 -1 (4000 1725)(1875 1725);
FORCEPROP 2 LAST SIG_NAME VR_PVDDQ_KLM_VD12
J 0
(3310 1740);
DISPLAY 0.617021 (3310 1740);
PAINT ORANGE (3310 1740);
WIRE 16 -1 (4000 1475)(1875 1475);
FORCEPROP 2 LAST SIG_NAME VR_PVDDQ_KLM_PWM1
J 0
(3300 1490);
DISPLAY 0.617021 (3300 1490);
PAINT ORANGE (3300 1490);
WIRE 16 -1 (1875 1425)(4000 1425);
FORCEPROP 2 LAST SIG_NAME VR_PVDDQ_KLM_PWM2
J 0
(3300 1440);
DISPLAY 0.617021 (3300 1440);
PAINT ORANGE (3300 1440);
WIRE 16 -1 (975 2525)(825 2525);
WIRE 16 -1 (825 3225)(825 2525);
WIRE 16 -1 (1125 3225)(825 3225);
WIRE 16 -1 (825 3425)(825 3225);
WIRE 16 -1 (1525 3225)(1125 3225);
FORCEPROP 2 LAST SIG_NAME VR_PVDDQ_KLM_VDD
J 0
(1085 3240);
DISPLAY 0.617021 (1085 3240);
PAINT ORANGE (1085 3240);
FORCEPROP 2 LASTPROP $XRERR UNIQUE?
J 0
(845 3240);
DISPLAY 0.638298 (845 3240);
PAINT MONO (845 3240);
DISPLAY INVISIBLE (845 3240);
WIRE 16 -1 (1125 3175)(1125 3225);
WIRE 16 -1 (1525 3175)(1525 3225);
WIRE 16 -1 (975 2225)(100 2225);
FORCEPROP 2 LAST SIG_NAME TP_PVDDQ_KLM_PH3_IMON_REF
J 0
(125 2240);
DISPLAY 0.617021 (125 2240);
PAINT ORANGE (125 2240);
FORCEPROP 2 LASTPROP $XRERR UNIQUE?
J 0
(-140 2225);
DISPLAY 0.638298 (-140 2225);
PAINT MONO (-140 2225);
DISPLAY INVISIBLE (-140 2225);
WIRE 16 -1 (-2200 1775)(25 1775);
FORCEPROP 2 LAST SIG_NAME A_TSENSE_PVDDQ_KLM
J 0
(-2225 1790);
DISPLAY 0.617021 (-2225 1790);
PAINT ORANGE (-2225 1790);
WIRE 16 -1 (25 1775)(975 1775);
WIRE 16 -1 (25 825)(25 1775);
WIRE 16 -1 (275 1325)(975 1325);
FORCEPROP 2 LAST SIG_NAME TP_PVDDQ_KLM_BVREF
J 0
(375 1340);
DISPLAY 0.617021 (375 1340);
PAINT ORANGE (375 1340);
FORCEPROP 2 LASTPROP $XRERR UNIQUE?
J 0
(35 1325);
DISPLAY 0.638298 (35 1325);
PAINT MONO (35 1325);
DISPLAY INVISIBLE (35 1325);
WIRE 16 -1 (275 1225)(975 1225);
FORCEPROP 2 LAST SIG_NAME TP_PVDDQ_KLM_RESET_N
J 0
(375 1240);
DISPLAY 0.617021 (375 1240);
PAINT ORANGE (375 1240);
FORCEPROP 2 LASTPROP $XRERR UNIQUE?
J 0
(35 1225);
DISPLAY 0.638298 (35 1225);
PAINT MONO (35 1225);
DISPLAY INVISIBLE (35 1225);
WIRE 16 -1 (975 2025)(125 2025);
FORCEPROP 2 LAST SIG_NAME TP_PVDDQ_KLM_PH3_IMON
J 0
(150 2040);
DISPLAY 0.617021 (150 2040);
PAINT ORANGE (150 2040);
FORCEPROP 2 LASTPROP $XRERR UNIQUE?
J 0
(-115 2025);
DISPLAY 0.638298 (-115 2025);
PAINT MONO (-115 2025);
DISPLAY INVISIBLE (-115 2025);
WIRE 16 -1 (275 1725)(975 1725);
FORCEPROP 2 LAST SIG_NAME TP_PVDDQ_KLM_BTSEN
J 0
(375 1740);
DISPLAY 0.617021 (375 1740);
PAINT ORANGE (375 1740);
FORCEPROP 2 LASTPROP $XRERR UNIQUE?
J 0
(35 1725);
DISPLAY 0.638298 (35 1725);
PAINT MONO (35 1725);
DISPLAY INVISIBLE (35 1725);
WIRE 16 -1 (275 1125)(975 1125);
FORCEPROP 2 LAST SIG_NAME TP_PVDDQ_KLM_BREF1
J 0
(375 1140);
DISPLAY 0.617021 (375 1140);
PAINT ORANGE (375 1140);
FORCEPROP 2 LASTPROP $XRERR UNIQUE?
J 0
(35 1125);
DISPLAY 0.638298 (35 1125);
PAINT MONO (35 1125);
DISPLAY INVISIBLE (35 1125);
WIRE 16 -1 (275 1575)(975 1575);
FORCEPROP 2 LAST SIG_NAME TP_PVDDQ_KLM_BVSEN
J 0
(375 1590);
DISPLAY 0.617021 (375 1590);
PAINT ORANGE (375 1590);
FORCEPROP 2 LASTPROP $XRERR UNIQUE?
J 0
(35 1575);
DISPLAY 0.638298 (35 1575);
PAINT MONO (35 1575);
DISPLAY INVISIBLE (35 1575);
WIRE 16 -1 (575 375)(575 925);
FORCEPROP 0 LAST SIG_NAME VR_PVDDQ_KLM_XADDR2
R 1
J 0
(565 385);
DISPLAY 0.617021 (565 385);
PAINT ORANGE (565 385);
FORCEPROP 2 LASTPROP $XRERR UNIQUE?
J 0
(325 385);
DISPLAY 0.638298 (325 385);
PAINT MONO (325 385);
DISPLAY INVISIBLE (325 385);
WIRE 16 -1 (575 925)(975 925);
WIRE 16 -1 (200 375)(200 975);
FORCEPROP 0 LAST SIG_NAME VR_PVDDQ_KLM_XADDR1
R 1
J 0
(190 410);
DISPLAY 0.617021 (190 410);
PAINT ORANGE (190 410);
FORCEPROP 2 LASTPROP $XRERR UNIQUE?
J 0
(-50 410);
DISPLAY 0.638298 (-50 410);
PAINT MONO (-50 410);
DISPLAY INVISIBLE (-50 410);
WIRE 16 -1 (200 975)(975 975);
WIRE 16 -1 (-2175 900)(-1500 900);
FORCEPROP 2 LAST SIG_NAME VSENSE_PVDDQ_KLM_N
J 0
(-2190 915);
DISPLAY 0.617021 (-2190 915);
PAINT ORANGE (-2190 915);
WIRE 16 -1 (-1500 900)(-575 900);
WIRE 16 -1 (-1500 925)(-1500 900);
WIRE 16 -1 (-575 900)(-575 1375);
WIRE 16 -1 (975 1375)(-575 1375);
WIRE 16 -1 (975 1875)(-425 1875);
WIRE 16 -1 (-425 525)(-425 1875);
WIRE 16 -1 (-425 1875)(-2200 1875);
FORCEPROP 2 LAST SIG_NAME VR_PVDDQ_KLM_AIINSEN
J 0
(-2210 1885);
DISPLAY 0.617021 (-2210 1885);
PAINT ORANGE (-2210 1885);
WIRE 16 -1 (-2200 2125)(975 2125);
FORCEPROP 2 LAST SIG_NAME ISENSE_PVDDQ_KLM_PH1_IMON
J 0
(-2225 2140);
DISPLAY 0.617021 (-2225 2140);
PAINT ORANGE (-2225 2140);
WIRE 16 -1 (-2200 2075)(975 2075);
FORCEPROP 2 LAST SIG_NAME ISENSE_PVDDQ_KLM_PH2_IMON
J 0
(-2225 2090);
DISPLAY 0.617021 (-2225 2090);
PAINT ORANGE (-2225 2090);
WIRE 16 -1 (975 1925)(-2200 1925);
FORCEPROP 2 LAST SIG_NAME VR_PVDDQ_KLM_VINSEN
J 0
(-2225 1940);
DISPLAY 0.617021 (-2225 1940);
PAINT ORANGE (-2225 1940);
DOT 1 (-1500 900);
DOT 1 (-1500 1175);
DOT 1 (-425 1875);
DOT 1 (-1825 2725);
DOT 1 (-1400 2325);
DOT 1 (-1475 3550);
DOT 1 (-1250 3550);
DOT 1 (-600 2275);
DOT 1 (-675 3050);
DOT 1 (75 1475);
DOT 1 (25 1775);
DOT 1 (2000 975);
DOT 1 (500 3775);
DOT 1 (825 3225);
DOT 1 (1125 3225);
DOT 1 (3750 350);
DOT 1 (3800 1675);
DOT 1 (2075 2425);
DOT 1 (2350 2525);
DOT 1 (2900 2525);
DOT 1 (2450 3525);
DOT 1 (2350 3525);
FORCENOTE
ROOM=VDDQ_KLM_PWR_VR
(-2730 -715) 0;
DISPLAY LEFT (-2730 -715);
DISPLAY 2.446809 (-2730 -715);
PAINT PURPLE (-2730 -715);
FORCENOTE
IOUT PK = 74A
(3950 3275) 0;
DISPLAY LEFT (3950 3275);
DISPLAY 0.808511 (3950 3275);
PAINT PURPLE (3950 3275);
FORCENOTE
IOUT STEP = 45A
(3950 3225) 0;
DISPLAY LEFT (3950 3225);
DISPLAY 0.808511 (3950 3225);
PAINT PURPLE (3950 3225);
FORCENOTE
IOUT DI/DT = 15A/US
(3950 3175) 0;
DISPLAY LEFT (3950 3175);
DISPLAY 0.808511 (3950 3175);
PAINT PURPLE (3950 3175);
FORCENOTE
AC & RIPPLE TOL = +/2.8%
(3950 3375) 0;
DISPLAY LEFT (3950 3375);
DISPLAY 0.808511 (3950 3375);
PAINT PURPLE (3950 3375);
FORCENOTE
RIPPLE GUIDELINE = +/- 0.5%
(3950 3475) 0;
DISPLAY LEFT (3950 3475);
DISPLAY 0.808511 (3950 3475);
PAINT PURPLE (3950 3475);
FORCENOTE
IOUT TDC = 63A
(3950 3325) 0;
DISPLAY LEFT (3950 3325);
DISPLAY 0.808511 (3950 3325);
PAINT PURPLE (3950 3325);
FORCENOTE
VOUT = 1.2V
(3950 3525) 0;
DISPLAY LEFT (3950 3525);
DISPLAY 0.808511 (3950 3525);
PAINT PURPLE (3950 3525);
FORCENOTE
DC TOL = +/-0.5%
(3950 3425) 0;
DISPLAY LEFT (3950 3425);
DISPLAY 0.808511 (3950 3425);
PAINT PURPLE (3950 3425);
FORCENOTE
SW FREQ = 833.33KHZ
(3950 3125) 0;
DISPLAY LEFT (3950 3125);
DISPLAY 0.808511 (3950 3125);
PAINT PURPLE (3950 3125);
QUIT
